G04 ================== begin FILE IDENTIFICATION RECORD ==================*
G04 Layout Name:  D:/<user>/Wistron_project/16342-2/gbr/16342-2.brd*
G04 Film Name:    L6*
G04 File Format:  Gerber RS274X*
G04 File Origin:  Cadence Allegro 16.5-S056*
G04 Origin Date:  Mon Aug 07 11:24:51 2017*
G04 *
G04 Layer:  VIA CLASS/L6*
G04 Layer:  PIN/L6*
G04 Layer:  ETCH/L6*
G04 Layer:  DRAWING FORMAT/LAYER_PCB_STORY*
G04 Layer:  DRAWING FORMAT/LAYER_L6*
G04 *
G04 Offset:    (0.00 0.00)*
G04 Mirror:    No*
G04 Mode:      Positive*
G04 Rotation:  0*
G04 FullContactRelief:  No*
G04 UndefLineWidth:     6.00*
G04 ================== end FILE IDENTIFICATION RECORD ====================*
%FSLAX35Y35*MOIN*%
%IR0*IPPOS*OFA0.00000B0.00000*MIA0B0*SFA1.00000B1.00000*%
%ADD11C,.02*%
%ADD15C,.03*%
%ADD13C,.022*%
%ADD14C,.042*%
%ADD16C,.026*%
%ADD12C,.018*%
%ADD10C,.028*%
%ADD17C,.01*%
%ADD18C,.025*%
%ADD19C,.004*%
%ADD20C,.005*%
%ADD21C,.006*%
%ADD22C,.0035*%
%ADD23C,.0055*%
%ADD25O,.15002X.21302*%
%ADD24O,.15004X.21304*%
G75*
%LPD*%
G75*
G36*
G01X6002Y722992D02*
X23394Y757778D01*
X38071D01*
G02X38288Y757043I0J-400D01*
G03X33556Y752780I10926J-16885D01*
G01X26483D01*
X11125Y722062D01*
X10896D01*
X10750Y721916D01*
Y721708D01*
X10896Y721562D01*
X11000D01*
Y11000D01*
X109197D01*
Y40396D01*
X109343Y40437D01*
G03Y48147I-1075J3855D01*
G01X109197Y48188D01*
Y428627D01*
X114196D01*
Y6002D01*
X6002D01*
Y722992D01*
G37*
G36*
G01X64870Y752780D02*
G03X60138Y757043I-15658J-12622D01*
G02X60355Y757778I217J335D01*
G01X353031D01*
G02X353248Y757043I0J-400D01*
G03X348516Y752780I10926J-16885D01*
G01X64870D01*
G37*
G36*
G01X914197Y721812D02*
X898714Y752780D01*
X891641D01*
G03X886909Y757043I-15658J-12622D01*
G02X887126Y757778I217J335D01*
G01X901803D01*
X919196Y722993D01*
Y6002D01*
X293522D01*
Y141799D01*
X298520D01*
Y11000D01*
X375188D01*
X379491Y6698D01*
X690405D01*
X694707Y11000D01*
X914197D01*
Y721812D01*
G37*
G36*
G01X397268Y702285D02*
Y719500D01*
X402266D01*
Y702285D01*
X397268D01*
G37*
G36*
G01X397143Y722062D02*
X381785Y752780D01*
X379830D01*
X379770Y752854D01*
G03X375098Y757043I-15598J-12696D01*
G02X375315Y757778I217J335D01*
G01X384874D01*
X402266Y722992D01*
Y722062D01*
X397143D01*
G37*
G36*
G01X566906Y176030D02*
G02X559273Y177976I-764J12946D01*
G01X554772D01*
Y182974D01*
X560897D01*
G03X574112Y188976I5245J6002D01*
G01Y293359D01*
G02X574790Y293647I400J0D01*
G03X579110Y290523I13007J13438D01*
G01Y188921D01*
X568677Y176806D01*
X566906Y176030D01*
G37*
G36*
G01X574112Y320815D02*
Y459656D01*
G02X574824Y459905I400J0D01*
G03X579110Y455901I15726J12537D01*
G01Y323651D01*
G03X574790Y320527I8687J-16562D01*
G02X574112Y320815I-278J288D01*
G37*
G36*
G01Y589134D02*
X591504Y623920D01*
X842520D01*
G03X852458Y633858I0J9938D01*
G01Y757778D01*
X864842D01*
G02X865059Y757043I0J-400D01*
G03X860387Y752854I10926J-16885D01*
G01X860327Y752780D01*
X857457D01*
Y747982D01*
X857441Y747944D01*
G03X857457Y732333I18543J-7787D01*
G01Y633858D01*
G02X842520Y618921I-14937J0D01*
G01X594593D01*
X579110Y587953D01*
Y488981D01*
G03X574824Y484977I11440J-16541D01*
G02X574112Y485226I-312J249D01*
G01Y589134D01*
G37*
G36*
G01X823383Y58743D02*
X811344Y46704D01*
X705087D01*
X704593Y46210D01*
X696877D01*
X688559Y54528D01*
Y108303D01*
X686755Y110107D01*
Y128805D01*
X708420Y150470D01*
X820224D01*
X823383Y147311D01*
Y58743D01*
G37*
G36*
G01X708870Y154596D02*
X693624Y169842D01*
Y368308D01*
X694652Y369336D01*
X709047Y383732D01*
X721677D01*
X726252Y388308D01*
X786998D01*
X796572Y378734D01*
X798672D01*
X822672Y354734D01*
Y166267D01*
X811001Y154596D01*
X708870D01*
G37*
%LPC*%
G75*
G54D25*
X706299Y83661D03*
Y201771D03*
G54D24*
X804724Y83661D03*
Y201772D03*
%LPD*%
G75*
G54D10*
X66435Y8514D03*
X61435D03*
X56435D03*
X51435D03*
X46435D03*
X41435D03*
X36435D03*
X31435D03*
X26435D03*
X21435D03*
X16435D03*
X8514Y10593D03*
Y15593D03*
Y20593D03*
Y25593D03*
Y30593D03*
Y35593D03*
Y40593D03*
Y45593D03*
Y50593D03*
Y55593D03*
Y60593D03*
Y65593D03*
Y70593D03*
Y75593D03*
Y80593D03*
Y85593D03*
Y90593D03*
Y95593D03*
Y100593D03*
Y105593D03*
Y110593D03*
Y115593D03*
Y120593D03*
Y125593D03*
Y130593D03*
Y135593D03*
Y140593D03*
Y145593D03*
Y150593D03*
Y155593D03*
Y160593D03*
Y165593D03*
Y170593D03*
Y175593D03*
Y180593D03*
Y185593D03*
Y190593D03*
Y195593D03*
Y200593D03*
Y205593D03*
Y210593D03*
Y215593D03*
Y220593D03*
Y225593D03*
Y230593D03*
Y235593D03*
Y240593D03*
Y245593D03*
Y250593D03*
Y255593D03*
Y260593D03*
Y265593D03*
Y270593D03*
Y275593D03*
Y280593D03*
Y285593D03*
Y290593D03*
Y295593D03*
Y300593D03*
Y305593D03*
Y310593D03*
Y315593D03*
Y320593D03*
Y325593D03*
Y330593D03*
Y335593D03*
Y340593D03*
Y345593D03*
Y350593D03*
Y355593D03*
Y360593D03*
Y365593D03*
Y370593D03*
Y375593D03*
Y380593D03*
Y385593D03*
Y390593D03*
Y395593D03*
Y400593D03*
Y405593D03*
Y410593D03*
Y415593D03*
Y420593D03*
Y425593D03*
Y430593D03*
Y435593D03*
Y440593D03*
Y445593D03*
Y450593D03*
Y455593D03*
Y460593D03*
Y465593D03*
Y470593D03*
Y475593D03*
Y480593D03*
Y485593D03*
Y490593D03*
Y495593D03*
Y500593D03*
Y505593D03*
Y510593D03*
Y515593D03*
Y520593D03*
Y525593D03*
Y530593D03*
Y535593D03*
Y540593D03*
Y545593D03*
Y550593D03*
Y555593D03*
Y560593D03*
Y565593D03*
Y570593D03*
Y575593D03*
Y580593D03*
Y585593D03*
Y590593D03*
Y595593D03*
Y600593D03*
Y605593D03*
Y610593D03*
Y615593D03*
Y620593D03*
Y625593D03*
Y630593D03*
Y635593D03*
Y640593D03*
Y645593D03*
Y650593D03*
Y655593D03*
Y660593D03*
Y665593D03*
Y670593D03*
Y675593D03*
Y680593D03*
Y685593D03*
Y690593D03*
Y695593D03*
Y700593D03*
Y705593D03*
Y710593D03*
Y715593D03*
Y720593D03*
X9942Y725256D03*
X12178Y729728D03*
X14414Y734200D03*
X16650Y738672D03*
X18886Y743144D03*
X21122Y747617D03*
X23358Y752089D03*
X111683Y63266D03*
Y58266D03*
Y23266D03*
Y18266D03*
Y13266D03*
X111435Y8514D03*
X106435D03*
X101435D03*
X96435D03*
X91435D03*
X86435D03*
X81435D03*
X76435D03*
X71435D03*
X111683Y118266D03*
Y113266D03*
Y108266D03*
Y103266D03*
Y98266D03*
Y93266D03*
Y88266D03*
Y83266D03*
Y78266D03*
Y73266D03*
Y68266D03*
Y203266D03*
Y198266D03*
Y193266D03*
Y188266D03*
Y183266D03*
Y178266D03*
Y173266D03*
Y168266D03*
Y163266D03*
Y158266D03*
Y153266D03*
Y148266D03*
Y278266D03*
Y273266D03*
Y268266D03*
Y263266D03*
Y258266D03*
Y253266D03*
Y248266D03*
Y243266D03*
Y238266D03*
Y233266D03*
Y228266D03*
Y223266D03*
Y218266D03*
Y213266D03*
Y208266D03*
Y348266D03*
Y343266D03*
Y338266D03*
Y333266D03*
Y328266D03*
Y323266D03*
Y318266D03*
Y313266D03*
Y308266D03*
Y303266D03*
Y298266D03*
Y293266D03*
Y288266D03*
Y283266D03*
Y418266D03*
Y413266D03*
Y408266D03*
Y403266D03*
Y398266D03*
Y393266D03*
Y388266D03*
Y383266D03*
Y378266D03*
Y373266D03*
Y368266D03*
Y363266D03*
Y358266D03*
Y353266D03*
X103940Y635460D03*
X76395Y755266D03*
X81395D03*
X86395D03*
X91395D03*
X96395D03*
X101395D03*
X106395D03*
X111395D03*
X116395D03*
X121395D03*
X126395D03*
X131395D03*
X136395D03*
X141395D03*
X146395D03*
X151395D03*
X156395D03*
X161395D03*
X166395D03*
X171395D03*
X176395D03*
X181395D03*
X186395D03*
X191395D03*
X196395D03*
X201395D03*
X206395D03*
X211395D03*
X216395D03*
X221395D03*
X226395D03*
X231395D03*
X236395D03*
X241395D03*
X246395D03*
X251395D03*
X256395D03*
X261395D03*
X266395D03*
X271395D03*
X276395D03*
X281395D03*
X330546Y8514D03*
X325546D03*
X320546D03*
X315546D03*
X310546D03*
X305546D03*
X300546D03*
X296034Y9002D03*
Y14002D03*
Y19002D03*
Y24002D03*
Y29002D03*
Y34002D03*
Y39002D03*
Y44002D03*
Y49002D03*
Y54002D03*
Y59002D03*
Y64002D03*
Y69002D03*
Y74002D03*
Y79002D03*
Y84002D03*
Y89002D03*
Y94002D03*
Y99002D03*
Y104002D03*
Y109002D03*
Y114002D03*
Y119002D03*
Y124002D03*
Y129002D03*
Y134002D03*
Y139002D03*
X334882Y190478D03*
X286395Y755266D03*
X291395D03*
X296395D03*
X301395D03*
X306395D03*
X311395D03*
X316395D03*
X321395D03*
X326395D03*
X331395D03*
X336395D03*
X399754Y706071D03*
X389168Y743572D03*
X391404Y739100D03*
X393640Y734628D03*
X395876Y730156D03*
X398112Y725684D03*
X399754Y716071D03*
Y711071D03*
X576624Y193205D03*
Y198205D03*
Y203205D03*
Y208205D03*
Y213205D03*
Y223205D03*
Y228205D03*
Y233205D03*
Y238205D03*
Y243205D03*
Y248205D03*
Y253205D03*
Y258205D03*
Y263205D03*
Y268205D03*
Y273205D03*
Y278205D03*
Y333205D03*
Y338205D03*
Y343205D03*
Y348205D03*
Y353205D03*
Y358205D03*
Y363205D03*
Y368205D03*
Y373205D03*
Y378205D03*
Y383205D03*
Y388205D03*
Y393205D03*
Y398205D03*
Y403205D03*
Y408205D03*
Y413205D03*
Y418205D03*
Y423205D03*
Y428205D03*
Y433205D03*
Y438205D03*
Y443205D03*
Y448205D03*
Y498205D03*
Y503205D03*
Y508205D03*
Y513205D03*
Y518205D03*
Y523205D03*
Y528205D03*
Y533205D03*
Y538205D03*
Y543205D03*
Y548205D03*
Y553205D03*
Y558205D03*
Y563205D03*
Y568205D03*
Y573205D03*
Y578205D03*
Y583205D03*
Y588205D03*
X578710Y592712D03*
X580946Y597184D03*
X583182Y601656D03*
X585418Y606129D03*
X587654Y610601D03*
X635975Y621407D03*
X640975D03*
X715546Y8514D03*
X710546D03*
X705546D03*
X700546D03*
X695546D03*
X663601Y51761D03*
X700065Y135985D03*
Y125985D03*
Y115985D03*
X710065D03*
Y125985D03*
Y135985D03*
Y155985D03*
Y145985D03*
X696159Y225829D03*
X698909Y278104D03*
X700065Y265985D03*
Y255985D03*
Y245985D03*
Y235985D03*
X710065D03*
Y245985D03*
Y255985D03*
Y265985D03*
X709625Y275991D03*
X710065Y325985D03*
Y315985D03*
X711574Y285985D03*
X708307Y295429D03*
X710065Y305985D03*
Y335985D03*
Y345985D03*
Y375985D03*
Y355985D03*
Y365985D03*
X689875Y464586D03*
X645975Y621407D03*
X650975D03*
X655975D03*
X660975D03*
X665975D03*
X670975D03*
X675975D03*
X680975D03*
X685975D03*
X690975D03*
X695975D03*
X700975D03*
X705975D03*
X710975D03*
X715975D03*
X785546Y8514D03*
X780546D03*
X775546D03*
X770546D03*
X765546D03*
X760546D03*
X755546D03*
X750546D03*
X745546D03*
X740546D03*
X735546D03*
X730546D03*
X725546D03*
X720546D03*
X770065Y55985D03*
Y65985D03*
Y75985D03*
X750065Y85985D03*
X770065D03*
X760065D03*
X740065D03*
X730065Y95985D03*
X760065D03*
X780065D03*
X770065D03*
Y105985D03*
X780065D03*
Y115985D03*
X730065Y135985D03*
Y125985D03*
Y115985D03*
Y105985D03*
X750065Y95985D03*
X740065D03*
X750065Y105985D03*
X760065D03*
X740065D03*
X750065Y115985D03*
X760065D03*
X770065D03*
X740065D03*
X750065Y125985D03*
X760065D03*
X770065D03*
X780065D03*
X740065D03*
X750065Y135985D03*
X760065D03*
X770065D03*
X780065D03*
X740065D03*
X720065Y105985D03*
Y115985D03*
Y125985D03*
Y135985D03*
Y155985D03*
X780065D03*
X730065D03*
Y145985D03*
X750065D03*
X760065D03*
X770065D03*
X780065D03*
X740065D03*
X750065Y155985D03*
X760065D03*
X770065D03*
X740065D03*
X750065Y165985D03*
X760065D03*
X770065D03*
X740065D03*
X750065Y175985D03*
X760065D03*
X770065D03*
X740065D03*
X750065Y185985D03*
X760065D03*
X770065D03*
X740065D03*
X750065Y195985D03*
X760065D03*
X770065D03*
X740065D03*
X750065Y205985D03*
X760065D03*
X770065D03*
X740065D03*
X720065Y145985D03*
X730065Y215985D03*
X773469Y277001D03*
X780065Y275985D03*
X787817Y275879D03*
X750065Y215985D03*
X760065D03*
X770065D03*
X780065D03*
X740065D03*
X780065Y265985D03*
Y255985D03*
Y245985D03*
Y235985D03*
Y225985D03*
X770065Y265985D03*
Y255985D03*
Y245985D03*
Y235985D03*
Y225985D03*
X763133Y275881D03*
X759790Y263326D03*
X760065Y255985D03*
Y245985D03*
Y235985D03*
Y225985D03*
X750065Y275985D03*
Y265985D03*
Y255985D03*
Y245985D03*
Y235985D03*
Y225985D03*
X741608Y277171D03*
X740065Y265985D03*
Y255985D03*
Y245985D03*
Y235985D03*
Y225985D03*
X730830Y276087D03*
X730065Y265985D03*
Y255985D03*
X731766Y246017D03*
X730065Y235985D03*
X730190Y223549D03*
X720237Y223228D03*
X720065Y235985D03*
X721766Y246017D03*
X720065Y255985D03*
Y265985D03*
X718617Y275736D03*
X770065Y335985D03*
X760065D03*
X720065Y325985D03*
X760065D03*
X750065D03*
X740065D03*
X730065D03*
X720065Y315985D03*
X780065Y285985D03*
X770065D03*
X760065D03*
X750065Y295985D03*
X760065D03*
X770065D03*
X780065D03*
Y305985D03*
Y315985D03*
Y325985D03*
Y335985D03*
Y345985D03*
X770065Y305985D03*
Y315985D03*
Y325985D03*
Y345985D03*
X760065Y305985D03*
Y315985D03*
Y345985D03*
X750065Y305985D03*
Y315985D03*
Y335985D03*
Y345985D03*
X740065Y305985D03*
Y315985D03*
Y335985D03*
Y345985D03*
X730065D03*
Y335985D03*
Y315985D03*
X752500Y286000D03*
X740065Y295985D03*
X741000Y286000D03*
X730065Y305985D03*
X729486Y296094D03*
X729294Y285987D03*
X721574Y285985D03*
X719049Y296011D03*
X720065Y305985D03*
Y335985D03*
Y345985D03*
Y375985D03*
X730065Y365985D03*
Y375985D03*
Y385985D03*
X750065D03*
X760065D03*
X770065D03*
X780065D03*
X740065D03*
X750065Y375985D03*
X760065D03*
X770065D03*
X780065D03*
X740065D03*
X750065Y365985D03*
X760065D03*
X770065D03*
X780065D03*
X740065D03*
X780065Y355985D03*
X770065D03*
X760065D03*
X750065D03*
X740065D03*
X730065D03*
X720065D03*
Y365985D03*
X720975Y621407D03*
X725975D03*
X730975D03*
X735975D03*
X740975D03*
X745975D03*
X750975D03*
X755975D03*
X760975D03*
X765975D03*
X770975D03*
X775975D03*
X780975D03*
X785975D03*
X850546Y8514D03*
X845546D03*
X840546D03*
X835546D03*
X830546D03*
X825546D03*
X820546D03*
X815546D03*
X810546D03*
X805546D03*
X800546D03*
X795546D03*
X790546D03*
X820065Y105985D03*
Y135985D03*
Y125985D03*
Y115985D03*
X810065Y135985D03*
Y125985D03*
Y115985D03*
X790065Y105985D03*
X800065Y115985D03*
X790065D03*
Y125985D03*
X800065D03*
Y135985D03*
X790065D03*
X810065Y155985D03*
X800065D03*
X790065D03*
X820065Y145985D03*
X810065D03*
X790065D03*
X800065D03*
X820313Y276188D03*
X810065Y275985D03*
X800065D03*
X820065Y265985D03*
Y255985D03*
Y245985D03*
Y235985D03*
Y225985D03*
X810065Y265985D03*
Y255985D03*
Y245985D03*
Y235985D03*
X800065Y265985D03*
Y255985D03*
Y245985D03*
Y235985D03*
X790065Y265985D03*
Y255985D03*
Y245985D03*
Y235985D03*
Y225985D03*
X820065Y305985D03*
Y295985D03*
Y285985D03*
X810065Y295985D03*
Y285985D03*
X800065D03*
X790065D03*
Y295985D03*
X800065D03*
X810065Y305985D03*
X810000Y314000D03*
X810065Y325985D03*
X800065Y305985D03*
Y315985D03*
Y325985D03*
Y335985D03*
Y345985D03*
X790065Y305985D03*
Y315985D03*
Y325985D03*
X791500Y336000D03*
X790065Y345985D03*
Y375985D03*
X800065D03*
X790065Y365985D03*
X800065D03*
Y355985D03*
X790065D03*
X809000Y429400D03*
X790975Y621407D03*
X795975D03*
X800975D03*
X805975D03*
X810975D03*
X815975D03*
X820975D03*
X825975D03*
X830975D03*
X835975D03*
X840975D03*
X854971Y637313D03*
Y642313D03*
Y647313D03*
Y652313D03*
Y657313D03*
Y662313D03*
Y667313D03*
Y672313D03*
Y677313D03*
Y682313D03*
Y687313D03*
Y692313D03*
Y697313D03*
Y702313D03*
Y707313D03*
Y712313D03*
X916683Y62377D03*
Y57377D03*
Y52377D03*
Y47377D03*
Y42377D03*
Y37377D03*
Y32377D03*
Y27377D03*
Y22377D03*
Y17377D03*
X915546Y8514D03*
X910546D03*
X905546D03*
X900546D03*
X916683Y132377D03*
Y127377D03*
Y122377D03*
Y117377D03*
Y112377D03*
Y107377D03*
Y102377D03*
Y97377D03*
Y92377D03*
Y87377D03*
Y82377D03*
Y77377D03*
Y72377D03*
Y67377D03*
Y207377D03*
Y202377D03*
Y197377D03*
Y192377D03*
Y187377D03*
Y182377D03*
Y177377D03*
Y172377D03*
Y167377D03*
Y162377D03*
Y157377D03*
Y152377D03*
Y147377D03*
Y142377D03*
Y137377D03*
Y277377D03*
Y272377D03*
Y267377D03*
Y262377D03*
Y257377D03*
Y252377D03*
Y247377D03*
Y242377D03*
Y237377D03*
Y232377D03*
Y227377D03*
Y222377D03*
Y217377D03*
Y212377D03*
Y347377D03*
Y342377D03*
Y337377D03*
Y332377D03*
Y327377D03*
Y322377D03*
Y317377D03*
Y312377D03*
Y307377D03*
Y302377D03*
Y297377D03*
Y292377D03*
Y287377D03*
Y282377D03*
Y422377D03*
Y417377D03*
Y412377D03*
Y407377D03*
Y402377D03*
Y397377D03*
Y392377D03*
Y387377D03*
Y382377D03*
Y377377D03*
Y372377D03*
Y367377D03*
Y362377D03*
Y357377D03*
Y352377D03*
Y492377D03*
Y487377D03*
Y482377D03*
Y477377D03*
Y472377D03*
Y467377D03*
Y462377D03*
Y457377D03*
Y452377D03*
Y447377D03*
Y442377D03*
Y437377D03*
Y432377D03*
Y427377D03*
Y562377D03*
Y557377D03*
Y552377D03*
Y547377D03*
Y542377D03*
Y537377D03*
Y532377D03*
Y527377D03*
Y522377D03*
Y517377D03*
Y512377D03*
Y507377D03*
Y502377D03*
Y497377D03*
Y637377D03*
Y632377D03*
Y627377D03*
Y622377D03*
Y617377D03*
Y612377D03*
Y607377D03*
Y602377D03*
Y597377D03*
Y592377D03*
Y587377D03*
Y582377D03*
Y577377D03*
Y572377D03*
Y567377D03*
Y707377D03*
Y702377D03*
Y697377D03*
Y692377D03*
Y687377D03*
Y682377D03*
Y677377D03*
Y672377D03*
Y667377D03*
Y662377D03*
Y657377D03*
Y652377D03*
Y647377D03*
Y642377D03*
X901041Y753684D03*
X903277Y749212D03*
X905513Y744740D03*
X907749Y740268D03*
X909985Y735796D03*
X912221Y731323D03*
X914457Y726851D03*
X916683Y722377D03*
Y717377D03*
Y712377D03*
G54D20*
G01X138023Y456188D02*
X133412D01*
X125750Y463850D01*
X111600D01*
X99831Y452081D01*
X62432D01*
X24657Y489856D01*
Y584229D01*
X42747Y602319D01*
X97312D01*
X98537Y601094D01*
G01X140985Y454250D02*
X132744D01*
X124644Y462350D01*
X112222D01*
X100453Y450581D01*
X61810D01*
X23157Y489234D01*
Y584851D01*
X42125Y603819D01*
X99790D01*
X102509Y601100D01*
G01X148490Y451286D02*
X147598Y450394D01*
X132356D01*
X123400Y459350D01*
X113466D01*
X101697Y447581D01*
X60566D01*
X20157Y487990D01*
Y586095D01*
X42634Y608572D01*
X103109D01*
G01X144245Y452344D02*
X132528D01*
X124022Y460850D01*
X112844D01*
X101075Y449081D01*
X61188D01*
X21657Y488612D01*
Y585473D01*
X41503Y605319D01*
X102958D01*
X103124Y605153D01*
G01X151877Y450439D02*
X150138Y448700D01*
X131928D01*
X122778Y457850D01*
X114088D01*
X102319Y446081D01*
X59944D01*
X18657Y487368D01*
Y586717D01*
X42639Y610699D01*
X101733D01*
X103098Y612064D01*
G01X155877Y450439D02*
X152438Y447000D01*
X131506D01*
X122286Y456220D01*
X114580D01*
X102941Y444581D01*
X59322D01*
X16620Y487283D01*
Y586802D01*
X42749Y612931D01*
X87757D01*
X88489Y612199D01*
X90933D01*
X103098Y624364D01*
G01X225532Y450047D02*
X223985Y448500D01*
X158200D01*
X154200Y444500D01*
X130470D01*
X121250Y453720D01*
X115616D01*
X103977Y442081D01*
X58286D01*
X57767Y442600D01*
X53925D01*
X14120Y482405D01*
Y486247D01*
X14119Y486248D01*
Y488318D01*
X14120Y488319D01*
Y587838D01*
X55282Y629000D01*
X70700D01*
G01X155343Y547283D02*
X138560Y530500D01*
X129800D01*
X126664Y527364D01*
X115535D01*
X112645Y524474D01*
X81853D01*
X67852Y538475D01*
Y539219D01*
G01X168898Y580315D02*
X167346Y581867D01*
X153933D01*
X152393Y583407D01*
X142623D01*
X138697Y587333D01*
X112906D01*
X111223Y585650D01*
X105250D01*
X95599Y575999D01*
Y572807D01*
X93807Y571015D01*
X76226D01*
X75892Y570681D01*
X73391D01*
X72833Y570123D01*
G01X162598Y567717D02*
X162384D01*
G03X161295Y567266I0J-1540D01*
G01X160695Y566666D01*
X160620Y566590D01*
G02X159595Y566166I-1025J1027D01*
G01X154009D01*
G03X151595Y565166I0J-3414D01*
G01X148971Y562542D01*
X130025D01*
Y562541D01*
X127380D01*
X126591Y563330D01*
X116362D01*
X114097Y561065D01*
X113389D01*
X112122Y562332D01*
X111414D01*
X110707Y561625D01*
Y560917D01*
X111974Y559650D01*
Y558942D01*
X111267Y558235D01*
X110559D01*
X109292Y559502D01*
X108584D01*
X107877Y558795D01*
Y558087D01*
X109144Y556820D01*
Y556112D01*
X106592Y553560D01*
X104395D01*
X103952Y554003D01*
X88654D01*
X88041Y553390D01*
G01X133554Y537374D02*
X134265D01*
X135090Y536549D01*
Y535030D01*
X134560Y534500D01*
X131127D01*
X130627Y535000D01*
Y537190D01*
X130127Y537690D01*
X129127D01*
X128627Y537190D01*
Y535000D01*
X128127Y534500D01*
X125550D01*
X125050Y535000D01*
Y536839D01*
X124515Y537374D01*
X123274D01*
X120400Y534500D01*
X117013D01*
X110987Y528474D01*
X83902D01*
X74760Y537616D01*
X72018D01*
X71971Y537569D01*
X70031D01*
X69743Y537857D01*
G01X162595Y564567D02*
G03X161764Y564429I-319J-650D01*
G02X161129Y564166I-635J635D01*
G01X155119D01*
X149494Y558541D01*
X125722D01*
X124933Y559330D01*
X118020D01*
X108250Y549560D01*
X96661D01*
X96167Y549066D01*
X84126D01*
X83262Y549930D01*
G01X100600Y490750D02*
X92750D01*
X87134Y496366D01*
X46979D01*
X26657Y516688D01*
Y583331D01*
X42550Y599224D01*
G01X193400Y463300D02*
Y467249D01*
X184549Y476100D01*
X154400D01*
X148100Y482400D01*
X141600D01*
X125400Y498600D01*
G01X237600Y455500D02*
X229164D01*
X228140Y454476D01*
X185024D01*
X181300Y458200D01*
X168380D01*
X154600Y471980D01*
X139008D01*
X135262Y475726D01*
G01X74151Y545516D02*
X77095Y548460D01*
X78671D01*
X80721Y546410D01*
X81537D01*
X82295Y547168D01*
X90866D01*
X92591Y545443D01*
X96089D01*
X96166Y545520D01*
X97427D01*
X97927Y546020D01*
Y546990D01*
X98427Y547490D01*
X99427D01*
X99927Y546990D01*
Y546020D01*
X100427Y545520D01*
X101427D01*
X101927Y546020D01*
Y546990D01*
X102427Y547490D01*
X103427D01*
X103927Y546990D01*
Y546020D01*
X104427Y545520D01*
X107039D01*
X116419Y554900D01*
X117374D01*
X117874Y555400D01*
Y556290D01*
X118374Y556790D01*
X119374D01*
X119874Y556290D01*
Y555400D01*
X120374Y554900D01*
X122637D01*
X124278Y556541D01*
X129749D01*
X130249Y556041D01*
Y555880D01*
X130749Y555380D01*
X131749D01*
X132249Y555880D01*
Y556041D01*
X132749Y556541D01*
X133749D01*
X134249Y556041D01*
Y555880D01*
X134749Y555380D01*
X135749D01*
X136249Y555880D01*
Y556041D01*
X136749Y556541D01*
X137749D01*
X138249Y556041D01*
Y555880D01*
X138749Y555380D01*
X139749D01*
X140249Y555880D01*
Y556041D01*
X140749Y556541D01*
X141749D01*
X142249Y556041D01*
Y555880D01*
X142749Y555380D01*
X143749D01*
X144249Y555880D01*
Y556041D01*
X144749Y556541D01*
X145749D01*
X146249Y556041D01*
Y555880D01*
X146749Y555380D01*
X147749D01*
X148249Y555880D01*
Y556041D01*
X148749Y556541D01*
X149570D01*
X152895Y559866D01*
G02X158855Y563183I7912J-7203D01*
G02X159895Y563066I328J-1768D01*
G03X160379Y562966I484J1121D01*
G01X162488D01*
G03X163695Y563466I0J1707D01*
G01X164195Y563966D01*
G02X165745Y564567I1456J-1456D01*
G01X126337Y554085D02*
X125152Y552900D01*
X117248D01*
X107868Y543520D01*
X94577D01*
X94154Y543943D01*
X92408D01*
G01X168895Y564567D02*
G03X169712Y564566I817J333744D01*
G01X169779D01*
G03X170495Y565282I0J716D01*
G01Y568312D01*
G03X169395Y569267I-1100J-156D01*
G01X165105D01*
G03X164198Y568360I0J-907D01*
G01Y567078D01*
G02X163286Y566166I-912J0D01*
G01X162502D01*
G03X161295Y565666I0J-1707D01*
G01X161095Y565466D01*
G02X160371Y565166I-724J724D01*
G01X154726D01*
G03X152795Y564366I0J-2731D01*
G01X148971Y560542D01*
X142484D01*
X132025Y560541D01*
X126551D01*
X125762Y561330D01*
X117191D01*
X107421Y551560D01*
X89879D01*
X88285Y549966D01*
X85984D01*
G01X71002Y539219D02*
X74713D01*
X83458Y530474D01*
X110158D01*
X116184Y536500D01*
X119571D01*
X122861Y539790D01*
X131930D01*
X132430Y540290D01*
Y542190D01*
X131930Y542690D01*
X130811D01*
X130311Y543190D01*
Y546700D01*
G01X74076Y535966D02*
Y535471D01*
X83073Y526474D01*
X111816D01*
X117842Y532500D01*
X137731D01*
X141656Y536425D01*
X141676D01*
X157875Y552624D01*
G01X75508Y542198D02*
Y541402D01*
X82937Y533973D01*
X84037D01*
X84537Y534473D01*
Y535920D01*
X85037Y536420D01*
X86037D01*
X86537Y535920D01*
Y534473D01*
X87037Y533973D01*
X88037D01*
X88537Y534473D01*
Y535920D01*
X89037Y536420D01*
X90037D01*
X90537Y535920D01*
Y534473D01*
X91037Y533973D01*
X93567D01*
X97114Y537520D01*
X111546D01*
X116176Y542150D01*
X119563D01*
X124313Y546900D01*
X127639D01*
X130037Y549298D01*
X151227D01*
X157863Y555934D01*
G02X159995Y556766I1786J-1428D01*
G03X161633Y557303I289J1886D01*
G01X162598Y558268D01*
G01X127300Y543200D02*
Y542290D01*
X126800Y541790D01*
X122032D01*
X118894Y538652D01*
X115507D01*
X109329Y532474D01*
X106222D01*
X105722Y532974D01*
Y534870D01*
X105222Y535370D01*
X104222D01*
X103722Y534870D01*
Y532974D01*
X103222Y532474D01*
X102222D01*
X101722Y532974D01*
Y534870D01*
X101222Y535370D01*
X100222D01*
X99722Y534870D01*
Y532974D01*
X99222Y532474D01*
X82731D01*
X74789Y540416D01*
X72954D01*
X71002Y542368D01*
G01X168898Y567717D02*
X168107Y566926D01*
G03X167295Y564966I1960J-1960D01*
G01Y564190D01*
G02X166995Y563466I-1024J0D01*
G02X165645Y562966I-1350J1573D01*
G03X164706Y562577I0J-1328D01*
G01X164645Y562516D01*
G03X164195Y561430I1085J-1086D01*
G01X164148Y561089D01*
Y560774D01*
X163241Y559867D01*
X162179D01*
X162170Y559866D01*
G03X161530Y559601I0J-905D01*
G01X160327Y558398D01*
G02X159195Y557966I-1580J2441D01*
G03X157569Y557140I453J-2905D01*
G01X157532Y557102D01*
G02X156599Y556552I-1536J1540D01*
G03X155714Y556186I0J-1253D01*
G01X150826Y551298D01*
X129208D01*
X126810Y548900D01*
X123484D01*
X118734Y544150D01*
X114156D01*
X109526Y539520D01*
X95763D01*
X93811Y537568D01*
X82611D01*
X76313Y543866D01*
G01X159449Y570866D02*
X157899Y572416D01*
X154444D01*
X148570Y566542D01*
X135209D01*
X134709Y567042D01*
Y569240D01*
X134209Y569740D01*
X133209D01*
X132709Y569240D01*
Y567042D01*
X132209Y566542D01*
X129394D01*
X128542Y567394D01*
X124675D01*
X124175Y567894D01*
Y571000D01*
X123675Y571500D01*
X122675D01*
X122175Y571000D01*
Y567894D01*
X121675Y567394D01*
X120086D01*
X119560Y567920D01*
Y569500D01*
X119060Y570000D01*
X115350D01*
X112899Y567549D01*
X110621D01*
X101966Y558894D01*
X94038D01*
X93242Y559690D01*
G01X168898Y577165D02*
X169640Y576423D01*
Y575080D01*
X168920Y574360D01*
X167700D01*
X165600Y576460D01*
Y577581D01*
X164466Y578715D01*
X155656D01*
X152882Y581489D01*
X146301D01*
X145310Y580498D01*
X141289D01*
X138071Y583716D01*
X113532D01*
X112466Y582650D01*
X106493D01*
X98587Y574744D01*
Y574522D01*
X94180Y570115D01*
X76599D01*
X76184Y569700D01*
X74029D01*
X73954Y569625D01*
G01X71002Y561266D02*
Y560358D01*
X71430Y559930D01*
X73140D01*
X73650Y560440D01*
Y561770D01*
X73000Y562420D01*
Y564980D01*
X73480Y565460D01*
X74900D01*
X76537Y567097D01*
Y568780D01*
X76972Y569215D01*
X91900D01*
X92760Y568355D01*
Y566880D01*
X93300Y566340D01*
X95410D01*
X95910Y566840D01*
Y568540D01*
X96594Y569224D01*
X98237D01*
X102511Y573498D01*
Y574425D01*
X107736Y579650D01*
X113709D01*
X114775Y580716D01*
X136523D01*
X140549Y576690D01*
X145020D01*
X145490Y576220D01*
Y573100D01*
X146010Y572580D01*
X149300D01*
X150430Y573710D01*
Y575066D01*
X150930Y575566D01*
X158916D01*
X159449Y576099D01*
Y577165D01*
G01X91490Y565990D02*
X92586Y564894D01*
X98150D01*
X106805Y573549D01*
X110413D01*
X112864Y576000D01*
X114301D01*
X114612Y576310D01*
X116018Y577716D01*
X134946D01*
X139162Y573500D01*
X142770D01*
X144757Y571513D01*
X150782D01*
X153816Y574547D01*
X161620D01*
X162412Y573755D01*
X163293D01*
X164260Y574722D01*
Y576570D01*
X163665Y577165D01*
X162598D01*
G01X165748Y580315D02*
Y579767D01*
X166787Y578728D01*
X172874D01*
X173595Y578007D01*
Y573015D01*
X173000Y572420D01*
X162210D01*
X161083Y573547D01*
X154225D01*
X150220Y569542D01*
X143200D01*
X142242Y570500D01*
X137919D01*
X137856Y570563D01*
X137632D01*
X133479Y574716D01*
X117261D01*
X116261Y573716D01*
X116260D01*
X115544Y573000D01*
X114107D01*
X111656Y570549D01*
X109378D01*
X100723Y561894D01*
X92143D01*
X91197Y562840D01*
G01X88547Y556540D02*
X89579Y555508D01*
X95404D01*
X96789Y556893D01*
X102794D01*
X110431Y564530D01*
X113814D01*
X114678Y565394D01*
X127713D01*
X128565Y564542D01*
X148571D01*
X151395Y567366D01*
G02X155982Y569266I4587J-4587D01*
G01X156032Y569316D01*
X162650D01*
G03X163545Y569616I0J1485D01*
G01X164123Y570194D01*
G02X165745Y570866I1622J-1622D01*
G01X165748D01*
G01X143415Y530143D02*
X146096Y527462D01*
Y523441D01*
X144000Y521345D01*
Y514967D01*
X136333Y507300D01*
X102601D01*
G01X162598Y561417D02*
X162123D01*
G03X161309Y561080I0J-1151D01*
G01X160395Y560166D01*
G02X159954Y559848I-1206J1208D01*
G02X158095Y559966I-828J1652D01*
G03X155109Y559280I-1171J-1743D01*
G01X149127Y553298D01*
X128379D01*
X125981Y550900D01*
X118077D01*
X108697Y541520D01*
X95987D01*
X94836Y540369D01*
X92498D01*
X92076Y540791D01*
G01X168898Y583464D02*
X167348Y585014D01*
X161949D01*
X161099Y584164D01*
X155283D01*
X146322Y593125D01*
X142897D01*
X140105Y590333D01*
X111663D01*
X109980Y588650D01*
X102593D01*
X98237Y584294D01*
X96800D01*
X94699Y582193D01*
Y573180D01*
X93434Y571915D01*
X79784D01*
X78870Y572829D01*
Y574407D01*
X79566Y575103D01*
X82362D01*
X83600Y573865D01*
G01X89899Y577014D02*
X89360Y577553D01*
Y584180D01*
X90580Y585400D01*
X94470D01*
X96300Y587230D01*
Y587938D01*
X94803Y589435D01*
Y590298D01*
X96009Y591504D01*
X96978D01*
X98422Y590060D01*
X99130D01*
X100720Y591650D01*
X108737D01*
X110420Y593333D01*
X114077D01*
X114577Y593833D01*
Y595680D01*
X115077Y596180D01*
X117077D01*
X117577Y595680D01*
Y593833D01*
X118077Y593333D01*
X120077D01*
X120577Y593833D01*
Y595680D01*
X121077Y596180D01*
X123077D01*
X123577Y595680D01*
Y593833D01*
X124077Y593333D01*
X126077D01*
X126577Y593833D01*
Y595680D01*
X127077Y596180D01*
X129077D01*
X129577Y595680D01*
Y593833D01*
X130077Y593333D01*
X132077D01*
X132577Y593833D01*
Y595680D01*
X133077Y596180D01*
X135077D01*
X135577Y595680D01*
Y593833D01*
X136077Y593333D01*
X138077D01*
X138577Y593833D01*
Y595680D01*
X139077Y596180D01*
X146907D01*
X154749Y588338D01*
Y585971D01*
X155656Y585064D01*
X160584D01*
X162134Y586614D01*
X162598D01*
G01X86750Y577014D02*
Y577970D01*
X86140Y578580D01*
Y580840D01*
X83270Y583710D01*
Y588370D01*
X84380Y589480D01*
X85420D01*
X85920Y589980D01*
Y592200D01*
X86420Y592700D01*
X88420D01*
X88920Y592200D01*
Y589980D01*
X89420Y589480D01*
X91760D01*
X92480Y590200D01*
Y593990D01*
X93140Y594650D01*
X107494D01*
X112344Y599500D01*
X146422D01*
X157734Y588188D01*
X167324D01*
X168898Y586614D01*
G01X124903Y613900D02*
X127100D01*
X127600Y613400D01*
X130322D01*
X134347Y617425D01*
X140347D01*
X146022Y623100D01*
X158717D01*
X168817Y633200D01*
X177117D01*
X182850Y638933D01*
Y639867D01*
X185096Y642113D01*
X185574D01*
X192061Y648600D01*
X212173D01*
X224523Y660950D01*
X260829D01*
X261529Y660250D01*
X269100D01*
X269980Y661130D01*
X328570D01*
X328600Y661100D01*
G01X379100Y703300D02*
X376300Y700500D01*
X336000D01*
X326950Y691450D01*
X305578D01*
X298678Y684550D01*
X270221D01*
X268972Y685799D01*
X261902D01*
X260751Y686950D01*
X235450D01*
X226300Y677800D01*
X216992D01*
X200492Y661300D01*
X183128D01*
X174728Y652900D01*
X160823D01*
X144422Y636499D01*
Y634760D01*
X136861Y627199D01*
X134693D01*
X124793Y617299D01*
G01X139500Y611200D02*
Y612334D01*
X147266Y620100D01*
X163421D01*
X166168Y622847D01*
X200586D01*
X217339Y639600D01*
X221068D01*
X222818Y641350D01*
X279453D01*
X280873Y642770D01*
X281823D01*
X281853Y642800D01*
X283387D01*
X283417Y642770D01*
X287405D01*
X288720Y641455D01*
G01X128700Y615500D02*
X130300D01*
X133725Y618925D01*
X139725D01*
X145400Y624600D01*
X157280D01*
X171150Y638470D01*
Y641167D01*
X172382Y642399D01*
X179080D01*
X186781Y650100D01*
X211551D01*
X223981Y662530D01*
X255530D01*
X257124Y664124D01*
X269076D01*
X270250Y662950D01*
X335250D01*
X336000Y662200D01*
G01X113672Y605134D02*
X116306Y602500D01*
X148452D01*
X156756Y594196D01*
Y592456D01*
X159448Y589764D01*
G01X133835Y609620D02*
X133800D01*
Y613200D01*
X136525Y615925D01*
X140969D01*
X146644Y621600D01*
X162799D01*
X165546Y624347D01*
X195247D01*
X210399Y639499D01*
X214131D01*
X215732Y641100D01*
X220446D01*
X222651Y643305D01*
X240664D01*
X251079Y653720D01*
X281152D01*
X284041Y650831D01*
X330207D01*
X333264Y653888D01*
X347598D01*
X352260Y658550D01*
X373150D01*
X378100Y663500D01*
X397800D01*
X398600Y662700D01*
G01X226475Y480400D02*
X226126Y480749D01*
X210208D01*
X200278Y490679D01*
X185045D01*
X181967Y487601D01*
X180433D01*
X177355Y490679D01*
X171896D01*
X171637Y490420D01*
X166651D01*
X161431Y485200D01*
X155710D01*
G01X380200Y457800D02*
X379100Y456700D01*
X350958D01*
X336758Y442500D01*
X302397D01*
X287747Y457150D01*
X271050D01*
X268377Y459823D01*
X257804D01*
X254327Y463300D01*
X230800D01*
X227200Y459700D01*
X215150D01*
X213926Y458476D01*
X212392D01*
X211168Y459700D01*
X203778D01*
X185078Y478400D01*
X172300D01*
G01X381400Y462000D02*
X380900Y462500D01*
X379900D01*
X376100Y458700D01*
X350129D01*
X335929Y444500D01*
X303226D01*
X285903Y461823D01*
X258633D01*
X255156Y465300D01*
X205305D01*
X196455Y474150D01*
X192157D01*
X182206Y484101D01*
X172900D01*
G01X389081Y475224D02*
X385157Y471300D01*
X380100D01*
X378600Y469800D01*
X372125D01*
X370525Y468200D01*
X350378D01*
X323978Y494600D01*
X305822D01*
X291422Y480200D01*
X266478D01*
X263228Y483450D01*
X237150D01*
X234709Y481009D01*
X229048D01*
X227221Y482836D01*
X210243D01*
X200900Y492179D01*
X173578D01*
X171637Y494120D01*
X168120D01*
X164100Y490100D01*
X150500D01*
X149000Y488600D01*
G01X344900Y442800D02*
X339887D01*
X337587Y440500D01*
X301568D01*
X286918Y455150D01*
X270221D01*
X267771Y457600D01*
X257000D01*
X253300Y461300D01*
X232135D01*
X227335Y456500D01*
X214779D01*
X214755Y456476D01*
X211563D01*
X211539Y456500D01*
X186784D01*
X181484Y461800D01*
X174137D01*
X171537Y464400D01*
G01X343050Y438900D02*
X342650Y438500D01*
X302397D01*
X302396Y438499D01*
X300740D01*
X286089Y453150D01*
X269392D01*
X266942Y455600D01*
X256171D01*
X255620Y456150D01*
X240867D01*
X236982Y452265D01*
X182635D01*
X179100Y455800D01*
G01X373576Y466300D02*
X371976Y464700D01*
X346729D01*
X346728Y464701D01*
X345072D01*
X338371Y458000D01*
X338242D01*
X335900Y455658D01*
Y455529D01*
X332371Y452000D01*
X306335D01*
X283935Y474400D01*
X263310D01*
X259910Y477800D01*
X249000D01*
X247200Y476000D01*
X241300D01*
X239800Y474500D01*
X220812D01*
X216812Y478500D01*
X208830D01*
X206615Y480715D01*
X206002Y481327D01*
X201600Y485729D01*
Y486500D01*
G01X198200D02*
Y486300D01*
X207700Y476800D01*
X207701D01*
X208001Y476500D01*
X215700D01*
X219900Y472300D01*
X246829D01*
X250130Y475601D01*
X259280D01*
X264381Y470500D01*
X285006D01*
X305506Y450000D01*
X333200D01*
X337900Y454700D01*
Y454829D01*
X339071Y456000D01*
X339200D01*
X345900Y462700D01*
X373404D01*
X373534Y462830D01*
G01X200650Y497862D02*
X201371Y497141D01*
Y495952D01*
X210438Y486885D01*
X229479D01*
X231414Y484950D01*
X263850D01*
X267100Y481700D01*
X290800D01*
X305200Y496100D01*
X324600D01*
X350613Y470087D01*
X369287D01*
X370900Y471700D01*
G01X381370Y465500D02*
X379900D01*
X375100Y460700D01*
X349300D01*
X335100Y446500D01*
X304055D01*
X286655Y463900D01*
X261300D01*
X253800Y471400D01*
X250880D01*
X248280Y468800D01*
X206756D01*
X190036Y485520D01*
G01X339900Y454000D02*
Y453800D01*
X334100Y448000D01*
X304677D01*
X287277Y465400D01*
X261922D01*
X254422Y472900D01*
X252302D01*
X252301Y472901D01*
X250259D01*
X247658Y470300D01*
X210800D01*
X195653Y485447D01*
X194411D01*
G01X252626Y469150D02*
X250776Y467300D01*
X206134D01*
X197284Y476150D01*
X192986D01*
X183035Y486101D01*
X165920D01*
X161378Y481559D01*
X153489D01*
G01X233664Y482859D02*
X230380D01*
X227990Y485249D01*
X214051D01*
X213915Y485385D01*
X209816D01*
X200742Y494459D01*
X175231D01*
X174040Y495650D01*
X166850D01*
X163200Y492000D01*
X148400D01*
X145000Y488600D01*
G01X275276Y494017D02*
X272654D01*
X271671Y495000D01*
X261971D01*
X261271Y494300D01*
X217403D01*
X213597Y498106D01*
X206598D01*
X202992Y501712D01*
X187915D01*
X185977Y503650D01*
X171511D01*
X166761Y498900D01*
G01X293600Y518400D02*
X290800D01*
X289300Y519900D01*
X236361D01*
X229065Y527196D01*
X205811D01*
X203610Y529397D01*
G01X171906Y534661D02*
X172067Y534500D01*
X201853D01*
X202003Y534650D01*
X220404D01*
X221443Y533611D01*
X228770D01*
X232883Y529498D01*
X253703D01*
X254003Y529198D01*
X254494D01*
G01X154400Y533500D02*
Y531000D01*
X157300Y528100D01*
X196000D01*
X200900Y523200D01*
X216600D01*
X232000Y507800D01*
X249379D01*
X250642Y509063D01*
X269100D01*
G01X293326Y494174D02*
X293302Y494150D01*
X277972D01*
X276105Y496017D01*
X273983D01*
X272800Y497200D01*
X259750D01*
X258850Y496300D01*
X231400D01*
X229350Y498350D01*
X218575D01*
X208375Y508550D01*
X202583D01*
X201183Y507150D01*
X189550D01*
X187100Y509600D01*
G01X288311Y496200D02*
X288294Y496217D01*
X278734D01*
X276934Y498017D01*
X274812D01*
X273629Y499200D01*
X258921D01*
X258021Y498300D01*
X232229D01*
X230179Y500350D01*
X219404D01*
X208153Y511601D01*
X197899D01*
X196300Y513200D01*
X195200D01*
G01X162537Y499000D02*
X168687Y505150D01*
X186599D01*
X188537Y503212D01*
X203761D01*
X207367Y499606D01*
X214219D01*
X218025Y495800D01*
X227800D01*
X228200Y496200D01*
G01X266664Y493000D02*
X262800D01*
X262100Y492300D01*
X216574D01*
X212768Y496106D01*
X205769D01*
X202163Y499712D01*
X187086D01*
X185148Y501650D01*
X174133D01*
X172283Y499800D01*
X170800D01*
G01X373700Y482700D02*
X373370D01*
X368270Y487800D01*
X345800D01*
X339900Y493700D01*
X335522D01*
X327122Y502100D01*
X298200D01*
X294800Y498700D01*
X279080D01*
X276580Y501200D01*
X257771D01*
X256871Y500300D01*
X233058D01*
X231008Y502350D01*
X220233D01*
X206683Y515900D01*
X181000D01*
X174700Y509600D01*
G01X209842Y564567D02*
X211442Y562967D01*
X212346D01*
X212348Y562969D01*
X213634D01*
X214541Y562062D01*
Y560826D01*
X215548Y559819D01*
X222280D01*
X226278Y555821D01*
X233879D01*
X235300Y554400D01*
X247405D01*
X249755Y552050D01*
X259921D01*
X260072Y551899D01*
X261728D01*
X261879Y552050D01*
X262350D01*
X265100Y554800D01*
X296140D01*
X301700Y549240D01*
X303660D01*
X305200Y547700D01*
Y545201D01*
X306001Y544400D01*
X310500D01*
X311600Y545500D01*
X330936D01*
X332698Y543738D01*
G01X158000Y499000D02*
X158872D01*
X166522Y506650D01*
X187221D01*
X189159Y504712D01*
X206400D01*
X207500Y505812D01*
G01X260900Y553900D02*
X258400Y556400D01*
X243800D01*
X240423Y559777D01*
X227216D01*
X220874Y566119D01*
X209201D01*
X208292Y565210D01*
Y562967D01*
X209842Y561417D01*
G01X200200Y529200D02*
X204200Y525200D01*
X222100D01*
X230400Y516900D01*
X278666D01*
X280966Y514600D01*
X302433D01*
X307433Y509600D01*
X315600D01*
X317400Y511400D01*
X328906D01*
X330106Y510200D01*
X337078D01*
X343478Y503800D01*
X345778D01*
X352986Y496592D01*
X368289D01*
X371971Y500274D01*
X380387D01*
X388123Y492538D01*
Y492432D01*
G01X293500Y522600D02*
X292022D01*
X291722Y522900D01*
X258000D01*
X255158Y525742D01*
X233436D01*
X229778Y529400D01*
X219700D01*
X218053Y531047D01*
X199713D01*
X198516Y529850D01*
X172557D01*
X165777Y536630D01*
Y542555D01*
G01X250445Y548551D02*
X248291Y550705D01*
X241205D01*
X240851Y550351D01*
X223072D01*
X219900Y553523D01*
X211438D01*
X209842Y555119D01*
G01X175197Y548821D02*
X176747Y547271D01*
Y545075D01*
X184002Y537820D01*
X198100D01*
X198991Y538711D01*
X223899D01*
X224611Y537999D01*
X230113D01*
X233945Y534167D01*
X242307D01*
X244311Y536171D01*
X257112D01*
X259641Y538700D01*
X267700D01*
X273800Y544800D01*
X286600D01*
X292300Y539100D01*
X304500D01*
X306000Y540600D01*
X312300D01*
G01X168898Y545669D02*
X170496Y544071D01*
X175840D01*
X182991Y536920D01*
X198473D01*
X199364Y537811D01*
X223526D01*
X224238Y537099D01*
X228891D01*
X233323Y532667D01*
X242929D01*
X244562Y534300D01*
X245370D01*
X245741Y534671D01*
X247275D01*
X247625Y534321D01*
X257400D01*
X260279Y537200D01*
X268322D01*
X274322Y543200D01*
X286000D01*
X292000Y537200D01*
X305000D01*
X306500Y538700D01*
X326083D01*
X326533Y538250D01*
X328394D01*
X329431Y539287D01*
X332940D01*
G01X150553Y512500D02*
Y513623D01*
X153230Y516300D01*
X178600D01*
X179700Y517400D01*
X211500D01*
X221400Y507500D01*
X226200D01*
X229400Y504300D01*
X288900D01*
X290000Y503200D01*
G01X148050Y523740D02*
X150134D01*
X152474Y521400D01*
X177000D01*
X179500Y518900D01*
X217800D01*
X230900Y505800D01*
X291300D01*
X293800Y503300D01*
G01X285833Y557629D02*
X285683Y557779D01*
X273593D01*
X267072Y564300D01*
X265929D01*
X265928Y564301D01*
X264272D01*
X264271Y564300D01*
X263900D01*
X260000Y560400D01*
X249200D01*
X246051Y563549D01*
X242309D01*
X242081Y563777D01*
X237371D01*
X237143Y563549D01*
X234051D01*
X232400Y565200D01*
X228336D01*
X221119Y572417D01*
X208291D01*
X206692Y574016D01*
G01X234943Y565199D02*
X233442Y566700D01*
X230201D01*
X221286Y575615D01*
X212348D01*
X211441Y576522D01*
Y578764D01*
X212992Y580315D01*
G01X265100Y562300D02*
X261200Y558400D01*
X244629D01*
X241252Y561777D01*
X235832D01*
X234732Y560677D01*
X232896D01*
X232379Y561194D01*
X227072D01*
X225950Y562316D01*
Y564526D01*
X221208Y569268D01*
X211393D01*
X209842Y567717D01*
G01X293500Y625600D02*
X289736D01*
X287936Y627400D01*
X258500D01*
X256679Y629221D01*
X246907D01*
X245878Y630250D01*
X231603D01*
X229653Y628300D01*
X223536D01*
X211135Y615899D01*
X208509D01*
X204960Y612350D01*
X197800D01*
X196100Y614050D01*
G01X293600Y629100D02*
X289772D01*
X288972Y629900D01*
X263000D01*
X259677Y633223D01*
X253159D01*
X252436Y632500D01*
X247164D01*
X246826Y632838D01*
X222521D01*
X218600Y628917D01*
Y627383D01*
X215917Y624700D01*
X214500D01*
X203900Y614100D01*
G01X144737Y630882D02*
Y631237D01*
X163900Y650400D01*
X175765D01*
X184165Y658800D01*
X201528D01*
X217928Y675200D01*
X227700D01*
X235000Y682500D01*
X268734D01*
X269184Y682050D01*
X299714D01*
X306614Y688950D01*
X363664D01*
G01X162750Y612217D02*
X163517Y611450D01*
X211850D01*
X225550Y625150D01*
X251300D01*
X251550Y624900D01*
X286900D01*
X289916Y621884D01*
X315366D01*
X332650Y639168D01*
Y641033D01*
X332200Y641483D01*
Y643800D01*
G01X164400Y609200D02*
X165750Y610550D01*
X212223D01*
X213473Y611800D01*
X241700D01*
X250563Y602937D01*
Y599222D01*
X253276Y596509D01*
X282688D01*
X283948Y597769D01*
X295026D01*
X298507Y601250D01*
X318256D01*
X321421Y604415D01*
Y605265D01*
G01X390500Y665800D02*
X377571D01*
X372321Y660550D01*
X351431D01*
X349056Y658175D01*
X331400D01*
X330125Y656900D01*
X303717D01*
X302028Y655211D01*
X282490D01*
X281981Y655720D01*
X250250D01*
X248750Y654220D01*
X228944D01*
X221112Y646388D01*
Y644595D01*
X219617Y643100D01*
X214903D01*
X213302Y641499D01*
X203116D01*
X197467Y635850D01*
X188150D01*
X182100Y629800D01*
G01X390500Y669200D02*
X378142D01*
X371492Y662550D01*
X347950D01*
X345575Y660175D01*
X330504D01*
X329428Y659099D01*
X270799D01*
X269950Y658250D01*
X234063D01*
X232263Y656450D01*
X224139D01*
X213556Y645867D01*
Y644582D01*
X212473Y643499D01*
X194582D01*
X191550Y640467D01*
Y639133D01*
X190267Y637850D01*
X186250D01*
X178200Y629800D01*
G01X401000Y676500D02*
X399550Y677950D01*
X343481D01*
X335311Y686120D01*
X308155D01*
X301315Y679280D01*
X290202D01*
X283372Y672450D01*
X261206D01*
X254286Y665530D01*
X221330D01*
X212300Y656500D01*
X206400D01*
X203000Y653100D01*
X185537D01*
X177836Y645399D01*
X166860D01*
X151291Y629830D01*
X148210D01*
G01X421653Y159055D02*
X400710Y179998D01*
Y223948D01*
X393500Y231158D01*
Y455900D01*
X402000Y464400D01*
Y667600D01*
X393150Y676450D01*
X341667D01*
X337367Y680750D01*
X331250D01*
X328380Y683620D01*
X307777D01*
X301336Y677179D01*
X290223D01*
X283994Y670950D01*
X261828D01*
X254908Y664030D01*
X223359D01*
X210929Y651600D01*
X186159D01*
X178458Y643899D01*
X167482D01*
X162391Y638808D01*
Y634874D01*
X153617Y626100D01*
X143176D01*
X141742Y624666D01*
G01X336387Y648987D02*
X335900Y648500D01*
X334283D01*
X330969Y645186D01*
X327503D01*
X313817Y631500D01*
X295100D01*
X287500Y639100D01*
X249422D01*
X247972Y637650D01*
X244333D01*
X242383Y639600D01*
X225667D01*
X224167Y638100D01*
X217961D01*
X201208Y621347D01*
X166790D01*
X164043Y618600D01*
X147888D01*
X144263Y614975D01*
Y609023D01*
G01X209842Y589763D02*
X211393Y591314D01*
X221486D01*
X226502Y586298D01*
X228051Y584750D01*
X234350D01*
X239250Y579850D01*
X246650D01*
X248800Y582000D01*
G01X268200Y578700D02*
X262971D01*
X261733Y577462D01*
X255440D01*
X253828Y575850D01*
X234484D01*
X231884Y578450D01*
X226663D01*
X220098Y585015D01*
X209200D01*
X208242Y584057D01*
Y581865D01*
X206692Y580315D01*
G01X209841D02*
X211391Y581865D01*
X221010D01*
X228575Y574300D01*
X235600D01*
X236700Y573200D01*
X262271D01*
X263221Y572250D01*
X269750D01*
X274668Y567332D01*
X291565D01*
X293970Y564927D01*
G01X151800Y610300D02*
X154729Y607371D01*
X207029D01*
X209841Y604559D01*
Y599212D01*
G01X342208Y714950D02*
X339706Y717452D01*
X335548D01*
X324550Y728450D01*
X267868D01*
X251168Y711750D01*
X188268D01*
X185792Y709274D01*
X185598D01*
G01X337481Y719818D02*
X326849Y730450D01*
X267039D01*
X250339Y713750D01*
X186550D01*
X182200Y709400D01*
G01X226475Y480400D02*
X227366Y479509D01*
X235331D01*
X237772Y481950D01*
X262606D01*
X265856Y478700D01*
X292044D01*
X306444Y493100D01*
X323356D01*
X349756Y466700D01*
X371147D01*
X372747Y468300D01*
X380564D01*
X381370Y469106D01*
X381276D01*
G01X254100Y440800D02*
X255750Y442450D01*
X259550D01*
X260100Y441900D01*
X290266D01*
X304867Y427299D01*
X313973D01*
X324191Y417081D01*
Y410085D01*
X317306Y403200D01*
X308485D01*
X296550Y391265D01*
Y190873D01*
X301800Y185623D01*
Y176574D01*
X319005Y159369D01*
Y43566D01*
X331523Y31048D01*
X364973D01*
X382371Y13650D01*
X687524D01*
X702574Y28700D01*
X788520D01*
X795572Y35752D01*
X816542D01*
X835530Y54740D01*
Y333416D01*
X839166Y337052D01*
Y345418D01*
X835530Y349054D01*
Y395728D01*
X819656Y411602D01*
X731266D01*
X709300Y433568D01*
Y445719D01*
X707083Y447936D01*
X706586D01*
X701183Y453339D01*
G01X704836D02*
X714000Y444175D01*
Y436483D01*
X736881Y413602D01*
X821698D01*
X837530Y397770D01*
Y349883D01*
X841718Y345695D01*
Y189318D01*
X837530Y185130D01*
Y139780D01*
X845410Y131900D01*
Y61791D01*
X817371Y33752D01*
X796401D01*
X789349Y26700D01*
X703403D01*
X688353Y11650D01*
X384858D01*
X384857Y11649D01*
X381543D01*
X364144Y29048D01*
X330694D01*
X313115Y46627D01*
Y135964D01*
X300748Y148331D01*
Y174797D01*
X299800Y175745D01*
Y184794D01*
X293800Y190794D01*
Y435537D01*
X289436Y439900D01*
X258650D01*
X257950Y440600D01*
G01X275113Y476513D02*
X265921D01*
X261984Y480450D01*
X238394D01*
X234944Y477000D01*
X226500D01*
G01X394700Y481700D02*
X387620D01*
X384398Y478478D01*
X349898D01*
X337676Y490700D01*
X334278D01*
X325878Y499100D01*
X303531D01*
X292381Y487950D01*
X235826D01*
X233976Y489800D01*
X231400D01*
G01X237903D02*
X272583D01*
X274933Y492150D01*
X294350D01*
X302800Y500600D01*
X326500D01*
X334900Y492200D01*
X338298D01*
X338498Y492000D01*
X338583D01*
X350605Y479978D01*
X383776D01*
X389098Y485300D01*
X394952D01*
G01X236400Y440800D02*
X240200Y444600D01*
X260600D01*
X261300Y443900D01*
X291095D01*
X305695Y429300D01*
X314801D01*
X327891Y416210D01*
Y409656D01*
X319435Y401200D01*
X309314D01*
X298550Y390436D01*
Y191702D01*
X302652Y187600D01*
X307700D01*
X309800Y185500D01*
Y171651D01*
X322123Y159328D01*
Y44521D01*
X322122Y44520D01*
Y43278D01*
X332352Y33048D01*
X365802D01*
X383200Y15650D01*
X686695D01*
X708797Y37752D01*
X815713D01*
X833483Y55522D01*
Y334198D01*
X837166Y337881D01*
Y344589D01*
X833530Y348225D01*
Y394899D01*
X818827Y409602D01*
X712481D01*
X698651Y423432D01*
Y428165D01*
G01X378200Y476600D02*
X377822Y476978D01*
X349276D01*
X337054Y489200D01*
X333656D01*
X325256Y497600D01*
X304397D01*
X293247Y486450D01*
X276250D01*
X273600Y483800D01*
X267122D01*
X264472Y486450D01*
X232036D01*
X230036Y488450D01*
X216450D01*
X214900Y490000D01*
G01X463479Y99412D02*
X457212D01*
X445150Y87350D01*
X413964D01*
X378650Y52036D01*
Y47624D01*
X365574Y34548D01*
X332974D01*
X323623Y43899D01*
Y159950D01*
X311300Y172273D01*
Y187439D01*
X306315Y192424D01*
X304375D01*
X300050Y196750D01*
Y389814D01*
X309936Y399700D01*
X320057D01*
X329391Y409034D01*
Y416832D01*
X314811Y431412D01*
X305705D01*
X285467Y451650D01*
X238489D01*
X237604Y450765D01*
X232579D01*
X231476Y449662D01*
G01X233850Y552201D02*
X231151Y554900D01*
X218554D01*
X216784Y556670D01*
X215547D01*
X214591Y557626D01*
Y558863D01*
X212991Y560463D01*
Y561419D01*
G01X260513Y564135D02*
X256348Y568300D01*
X232266D01*
X221851Y578715D01*
X214655D01*
X213105Y577165D01*
X212991D01*
G01X390651Y499000D02*
X383901Y505750D01*
X371323D01*
X358573Y518500D01*
X348556D01*
X343056Y524000D01*
X327700D01*
X326301Y525399D01*
X320857D01*
X319156Y527100D01*
X297200D01*
X295850Y525750D01*
Y522150D01*
X294200Y520500D01*
X291200D01*
X290300Y521400D01*
X250951D01*
X248459Y523892D01*
G01X257894Y529254D02*
X261248Y525900D01*
X280500D01*
X284700Y530100D01*
X320400D01*
X322101Y528399D01*
X327744D01*
X329143Y527000D01*
X344300D01*
X347050Y524250D01*
X357682D01*
X361782Y520150D01*
X380917D01*
X385953Y515114D01*
X390786D01*
X397650Y508250D01*
G01Y536671D02*
X382100D01*
X374003Y544768D01*
X342129D01*
X334689Y537328D01*
X329594D01*
X329016Y536750D01*
X325911D01*
X325461Y537200D01*
X309564D01*
X308064Y535700D01*
X277378D01*
X276878Y535200D01*
X263750D01*
X263600Y535350D01*
G01X304436Y564081D02*
X301282Y560927D01*
X291533D01*
X289299Y563161D01*
X273162D01*
X268247Y568076D01*
X262694D01*
G01X307350Y561290D02*
Y563784D01*
X305203Y565931D01*
X301787D01*
X298783Y562927D01*
X292362D01*
X289957Y565332D01*
X273839D01*
X268921Y570250D01*
X262350D01*
X261300Y571300D01*
G01X406400Y150300D02*
X407300Y151200D01*
Y162600D01*
X398570Y171330D01*
Y223966D01*
X392000Y230536D01*
Y434300D01*
X389350Y436950D01*
Y448351D01*
X385301Y452400D01*
Y459538D01*
X386463Y460700D01*
X389900D01*
X397000Y467800D01*
Y495583D01*
X374283Y518300D01*
X360895D01*
X356445Y522750D01*
X346428D01*
X343678Y525500D01*
X328521D01*
X327122Y526899D01*
X321479D01*
X319778Y528600D01*
X285322D01*
X281122Y524400D01*
X258622D01*
X255780Y527242D01*
X234058D01*
X233505Y527795D01*
X233086D01*
X229281Y531600D01*
X223800D01*
G01X335000Y497000D02*
X328400Y503600D01*
X297400D01*
X294000Y500200D01*
X279702D01*
X277202Y502700D01*
X257000D01*
X256450Y502150D01*
X236400D01*
G01X246508Y532821D02*
X257379D01*
X260550Y529650D01*
X273450D01*
X277250Y533450D01*
X279967D01*
X280317Y533100D01*
X325164D01*
X328365Y529899D01*
X328366D01*
X329765Y528500D01*
X338400D01*
X339814Y529914D01*
X375936D01*
X387700Y518150D01*
Y517700D01*
G01X302665Y547006D02*
X301812D01*
X295818Y553000D01*
X270500D01*
X264201Y546701D01*
X239695D01*
X237576Y548820D01*
X222441D01*
G01X302506Y543341D02*
X294547Y551300D01*
X276000D01*
X269088Y544388D01*
X239886D01*
X237124Y547150D01*
X220961D01*
X219291Y548820D01*
G01X228100Y545500D02*
X229850Y543750D01*
X236650D01*
X242650Y537750D01*
X256567D01*
X261517Y542700D01*
X269522D01*
X273922Y547100D01*
X290190D01*
X296667Y540623D01*
X303623D01*
X305800Y542800D01*
X323800D01*
X324499Y543499D01*
X327403D01*
G01X327800Y514900D02*
X314583D01*
X311183Y518300D01*
X296500D01*
X294300Y516100D01*
X281588D01*
X279288Y518400D01*
X234100D01*
X227100Y525400D01*
G01X323400Y507540D02*
X323340D01*
X322400Y506600D01*
X306056D01*
X301256Y511400D01*
X279922D01*
X278172Y513150D01*
X242388D01*
X239138Y509900D01*
X238600D01*
G01X336800Y506300D02*
X334500Y508600D01*
X328700D01*
X327400Y509900D01*
X319300D01*
X317500Y508100D01*
X306678D01*
X301877Y512901D01*
X280543D01*
X278794Y514650D01*
X238066D01*
X233216Y509800D01*
X233100D01*
G01X335000Y500600D02*
X333800D01*
X329300Y505100D01*
X305434D01*
X300634Y509900D01*
X279300D01*
X277550Y511650D01*
X244450D01*
X242600Y509800D01*
G01X212992Y564567D02*
X213950D01*
X215498Y563019D01*
X222701D01*
X228049Y557671D01*
X233607D01*
G01X366490Y564360D02*
X354092D01*
X351632Y561900D01*
X324990D01*
X321290Y558200D01*
X287900D01*
X286016Y560084D01*
X273410D01*
X267500Y565994D01*
X261947D01*
X256991Y570950D01*
X235850D01*
X234800Y572000D01*
G01X216142Y545669D02*
X220308D01*
X227078Y538899D01*
X230486D01*
X231327Y538058D01*
X239113D01*
X241154Y536017D01*
G01X279200Y531600D02*
X321900D01*
X322900Y530600D01*
G01X366100Y590000D02*
X364200D01*
X362091Y592109D01*
X360163D01*
X354787Y597485D01*
X346249D01*
X343573Y594809D01*
X325236D01*
X320545Y599500D01*
X298879D01*
X295648Y596269D01*
X284570D01*
X283310Y595009D01*
X248392D01*
X239654Y603747D01*
X233447D01*
G01X366500Y586300D02*
X364300D01*
X361018Y589582D01*
X359886D01*
X353483Y595985D01*
X346871D01*
X341995Y591109D01*
X324994D01*
X318103Y598000D01*
X299501D01*
X296270Y594769D01*
X285192D01*
X283932Y593509D01*
X247392D01*
X240601Y600300D01*
X232300D01*
G01X336923Y586749D02*
X325719D01*
X320480Y591988D01*
X299147D01*
X294066Y586907D01*
X270354D01*
X269712Y586265D01*
X258687D01*
X258596Y586356D01*
G01X259848Y583194D02*
X269470D01*
X271182Y584906D01*
X297806D01*
X302888Y589988D01*
X319651D01*
X326290Y583349D01*
X336923D01*
G01X279214Y591383D02*
X289819D01*
X291205Y592769D01*
X297099D01*
X300330Y596000D01*
X307650D01*
G01X285400Y572556D02*
X285244D01*
X284430Y573370D01*
Y577170D01*
X278694Y582906D01*
X272011D01*
X269805Y580700D01*
X256891D01*
X255491Y582100D01*
X252000D01*
X247750Y577850D01*
X234750D01*
X232750Y579850D01*
X229203D01*
X220653Y588400D01*
X216900D01*
X216141Y589159D01*
Y589762D01*
G01X237100Y590000D02*
X237000Y589900D01*
X227500D01*
X223300Y594100D01*
X216700D01*
X215512Y592912D01*
X212993D01*
G01X281975Y572963D02*
X279171D01*
X278490Y572282D01*
X275376D01*
X271408Y576250D01*
X263350D01*
X262562Y575462D01*
X256419D01*
X256007Y575050D01*
G01X279800Y569182D02*
X279082Y569900D01*
X274929D01*
X270579Y574250D01*
X264350D01*
X264200Y574100D01*
G01X230600Y608100D02*
X229600Y607100D01*
Y599900D01*
X231200Y598300D01*
X234067D01*
X244617Y587750D01*
X250853D01*
X253853Y590750D01*
X267946D01*
X269789Y588907D01*
X276783D01*
G01X317813Y584969D02*
X312544Y579700D01*
X295396D01*
X292200Y582896D01*
X281617D01*
X281510Y583003D01*
G01X254900Y701950D02*
X271250D01*
X272550Y700650D01*
X276400D01*
G01X217638Y695562D02*
X219800Y693400D01*
X260666D01*
X263535Y690531D01*
X297531D01*
X304054Y697054D01*
X323554D01*
X328087Y701587D01*
G01X327062Y697600D02*
X322912Y693450D01*
X304749D01*
X299830Y688531D01*
X261999D01*
X261580Y688950D01*
X241050D01*
X239000Y691000D01*
G01X392079Y703434D02*
X386963Y708550D01*
X326103D01*
X320107Y702554D01*
X301774D01*
X299670Y700450D01*
X297126D01*
X297022Y700554D01*
X292586D01*
X292482Y700450D01*
X281800D01*
X273350Y708900D01*
X254700D01*
G01X372500Y44500D02*
X365003Y37003D01*
X333348D01*
X329018Y41333D01*
Y157384D01*
X313300Y173102D01*
Y226038D01*
X315000Y227738D01*
Y364553D01*
X314200Y365353D01*
Y380803D01*
X320272Y386875D01*
X320419D01*
X321859Y388315D01*
G01X372500Y56500D02*
Y47388D01*
X364115Y39003D01*
X334177D01*
X331018Y42162D01*
Y158213D01*
X315300Y173931D01*
Y225209D01*
X317000Y226909D01*
Y365382D01*
X316200Y366182D01*
Y379974D01*
X321100Y384874D01*
G01X294720Y178600D02*
X296300Y177020D01*
Y174294D01*
X297198Y173396D01*
Y146930D01*
X309615Y134513D01*
Y48078D01*
X309614Y48077D01*
Y45177D01*
X329243Y25548D01*
X362693D01*
X380092Y8149D01*
X386308D01*
X386309Y8150D01*
X689804D01*
X703954Y22300D01*
X762583D01*
X765533Y19350D01*
X767067D01*
X770017Y22300D01*
X789900D01*
X797852Y30252D01*
X818822D01*
X849300Y60730D01*
Y195200D01*
X845418Y199082D01*
Y345418D01*
X848500Y348500D01*
Y352713D01*
X844766Y356447D01*
Y459234D01*
X801199Y502801D01*
X784199D01*
X777165Y509835D01*
G01X294720Y185600D02*
X297800Y182520D01*
Y174916D01*
X298698Y174018D01*
Y147552D01*
X311115Y135135D01*
Y47456D01*
X311114Y47455D01*
Y45799D01*
X329865Y27048D01*
X363315D01*
X380714Y9649D01*
X385686D01*
X385687Y9650D01*
X689182D01*
X704032Y24500D01*
X789978D01*
X797230Y31752D01*
X818200D01*
X847410Y60962D01*
Y194968D01*
X843918Y198460D01*
Y348729D01*
X840159Y352488D01*
Y460744D01*
X799603Y501300D01*
X686200D01*
X678740Y508760D01*
G01X352000Y109000D02*
X345281Y115719D01*
Y158305D01*
X328600Y174986D01*
Y196414D01*
X330911Y198725D01*
Y236035D01*
X328800Y238146D01*
Y268896D01*
X333882Y273978D01*
G01X355500Y109000D02*
X351305Y113195D01*
Y116695D01*
X346781Y121219D01*
Y158927D01*
X330100Y175608D01*
Y195792D01*
X332411Y198103D01*
Y237242D01*
X330300Y239353D01*
Y266996D01*
X333882Y270578D01*
G01X372500Y90000D02*
X374500Y92000D01*
Y99600D01*
X367600Y106500D01*
X350964D01*
X342781Y114683D01*
Y157208D01*
X326100Y173889D01*
Y197450D01*
X328350Y199700D01*
Y235060D01*
X326300Y237110D01*
Y380111D01*
X327889Y381700D01*
X329900D01*
X331950Y379650D01*
X346114D01*
X374030Y407566D01*
Y449526D01*
G01X372500Y78000D02*
X370200Y80300D01*
Y92100D01*
X372000Y93900D01*
Y98564D01*
X368264Y102300D01*
X343595D01*
X336573Y109322D01*
Y159023D01*
X323600Y171996D01*
Y198486D01*
X325850Y200736D01*
Y233478D01*
X323800Y235528D01*
Y381147D01*
X326853Y384200D01*
X330936D01*
X332986Y382150D01*
X345078D01*
X371500Y408572D01*
Y451525D01*
X372575Y452600D01*
G01X498500Y84200D02*
X487000D01*
X468700Y102500D01*
X457471D01*
X445600Y90629D01*
X394254D01*
X353100Y131783D01*
Y160837D01*
X340750Y173187D01*
Y253450D01*
X332481Y261719D01*
Y265877D01*
X333782Y267178D01*
G01X353543Y70787D02*
Y73057D01*
X347000Y79600D01*
X338500D01*
X333317Y84783D01*
Y154555D01*
X333318Y154556D01*
Y158742D01*
X317300Y174760D01*
Y224380D01*
X319000Y226080D01*
Y366211D01*
X318200Y367011D01*
Y379137D01*
X325763Y386700D01*
X346092D01*
X369000Y409608D01*
Y452900D01*
X370800Y454700D01*
X374882D01*
X377691Y451891D01*
G01X501100Y86800D02*
X487300D01*
X469600Y104500D01*
X456642D01*
X444771Y92629D01*
X401765D01*
X355300Y139094D01*
Y161466D01*
X342750Y174016D01*
Y255510D01*
X334482Y263778D01*
G01X320700Y177800D02*
X318800Y179700D01*
Y211268D01*
X321242Y213710D01*
Y221892D01*
X322150Y222800D01*
X324000D01*
G01X328313Y435513D02*
Y433987D01*
X333391Y428909D01*
Y407331D01*
X321560Y395500D01*
X313000D01*
X310430Y392930D01*
Y385670D01*
X308700Y383940D01*
Y363073D01*
X309317Y362456D01*
Y237709D01*
X305882Y234274D01*
G01X324916Y435360D02*
Y434555D01*
X331391Y428080D01*
Y408205D01*
X320886Y397700D01*
X310765D01*
X302050Y388985D01*
Y241395D01*
X305772Y237673D01*
G01X350408Y393708D02*
X350400Y393716D01*
Y394300D01*
X367500Y411400D01*
Y453045D01*
X366700Y453845D01*
Y454800D01*
G01X348006Y391300D02*
X348000Y391306D01*
Y394022D01*
X366000Y412022D01*
Y452423D01*
X365081Y453342D01*
X361142D01*
X359400Y451600D01*
G01X378937Y443491D02*
Y406108D01*
X347429Y374600D01*
X346300D01*
G01X376697Y446050D02*
Y406697D01*
X349100Y379100D01*
G01X355600Y506600D02*
X352570Y509630D01*
X343770D01*
X339200Y514200D01*
X331764D01*
X327414Y518550D01*
X316397D01*
X313850Y521097D01*
Y521114D01*
X312964Y522000D01*
X302436D01*
X302335Y521899D01*
X300265D01*
X300164Y522000D01*
X299100D01*
X298200Y521100D01*
G01X355600Y513500D02*
X346484D01*
X343284Y516700D01*
X332800D01*
X328450Y521050D01*
X317433D01*
X316350Y522133D01*
Y522150D01*
X313900Y524600D01*
X301500D01*
X301300Y524400D01*
G01X327300Y540100D02*
X328565Y541365D01*
X333366D01*
X339166Y547165D01*
X343824D01*
X343825Y547164D01*
X349627D01*
X356693Y554230D01*
X361920D01*
X362280Y554590D01*
G01X397650Y519400D02*
X390300Y526750D01*
Y530190D01*
X387819Y532671D01*
X349544D01*
X348865Y533350D01*
X344015D01*
X342579Y531914D01*
X338299D01*
X336881Y530496D01*
G01X307800Y546700D02*
X314480Y553380D01*
X324110D01*
X326150Y555420D01*
X336764D01*
X340019Y552165D01*
X345897D01*
X345898Y552164D01*
X347554D01*
X355750Y560360D01*
X364078D01*
X364929Y559509D01*
X368041D01*
X368732Y560200D01*
X374500D01*
X374650Y560050D01*
X374790D01*
X381840Y553000D01*
X390550D01*
X391351Y552200D01*
X393775Y549776D01*
Y549775D01*
X394880Y548670D01*
G01X397650Y523900D02*
X392359Y529191D01*
Y530960D01*
X388648Y534671D01*
X350373D01*
X349694Y535350D01*
X343186D01*
X342186Y534350D01*
X337109D01*
X336953Y534506D01*
G01X305913Y549643D02*
X306557Y550287D01*
Y550336D01*
X311601Y555380D01*
X323281D01*
X325321Y557420D01*
X337593D01*
X340848Y554165D01*
X346726D01*
X354921Y562360D01*
X364907D01*
X365757Y561510D01*
X367213D01*
X368003Y562300D01*
X374099D01*
X374199Y562200D01*
X375329D01*
X375479Y562050D01*
X375619D01*
X380869Y556800D01*
X383999D01*
X385799Y555000D01*
X391378D01*
X392765Y553615D01*
X393280Y553100D01*
X393465D01*
G01X365730Y541050D02*
X357131D01*
X355583Y539502D01*
X339250D01*
X335459Y535711D01*
X330711D01*
X330200Y535200D01*
G01X331000Y522100D02*
X332000Y521100D01*
X335100D01*
X337000Y519200D01*
X344320D01*
X347520Y516000D01*
X357536D01*
X368536Y505000D01*
X368900D01*
G01X293970Y564927D02*
X297954D01*
X301127Y568100D01*
X310600D01*
X312400Y569900D01*
X344760D01*
X345870Y568790D01*
X367200D01*
X367632Y569222D01*
X379090D01*
X383126Y565186D01*
Y565162D01*
G01X396400Y545500D02*
X395221D01*
X389721Y551000D01*
X381011D01*
X373961Y558050D01*
X369411D01*
X368360Y556999D01*
X364610D01*
X363249Y558360D01*
X356579D01*
X348383Y550164D01*
X345069D01*
X345068Y550165D01*
X338836D01*
X337525Y551476D01*
X334811D01*
G01X311900Y511500D02*
X313300Y512900D01*
X329528D01*
X330728Y511700D01*
X337700D01*
X344100Y505300D01*
X346400D01*
X353608Y498092D01*
X367667D01*
X371349Y501774D01*
X384374D01*
X390769Y495379D01*
G01X393889Y543207D02*
Y544710D01*
X389099Y549500D01*
X380389D01*
X373339Y556550D01*
X370033D01*
X368982Y555499D01*
X363988D01*
X363047Y556440D01*
X356781D01*
X349005Y548664D01*
X344447D01*
X344446Y548665D01*
X337465D01*
X336650Y547850D01*
X327911D01*
X327417Y548344D01*
G01X303000Y586800D02*
X303512Y586288D01*
X310242D01*
X311454Y587500D01*
X318111D01*
X322198Y583413D01*
Y581685D01*
X325784Y578099D01*
X338339D01*
X339324Y579084D01*
X345349D01*
X347708Y576725D01*
X368488D01*
X371865Y580102D01*
X375700D01*
G01X380572Y592095D02*
X375371D01*
X366426Y583150D01*
X363376D01*
X355991Y590535D01*
X352716D01*
G01X396300Y587000D02*
X394000Y584700D01*
X370805D01*
X366841Y580736D01*
X359839D01*
X354342Y586233D01*
X349060D01*
X347784Y587509D01*
G01X396400Y583500D02*
X395300Y582400D01*
X386917D01*
X386867Y582450D01*
X385333D01*
X385283Y582400D01*
X371334D01*
X367670Y578736D01*
X359010D01*
X353637Y584109D01*
X347784D01*
G01X317813Y580469D02*
X314444Y577100D01*
X297200D01*
X291132Y571032D01*
X288232D01*
X286400Y569200D01*
G01X395127Y568056D02*
X394283Y568900D01*
X387799D01*
X385477Y571222D01*
X368479D01*
X366976Y572725D01*
X358963D01*
X357225Y570987D01*
X346502D01*
X344768Y572721D01*
X343112D01*
X343111Y572720D01*
X325505D01*
X317813Y580412D01*
Y580469D01*
G01X395100Y572899D02*
X393600D01*
X393277Y573222D01*
X369308D01*
X367805Y574725D01*
X358134D01*
X356396Y572987D01*
X347331D01*
X343234Y577084D01*
X340153D01*
X338889Y575820D01*
X325234D01*
X320198Y580856D01*
Y582584D01*
X317813Y584969D01*
G01X317516Y671612D02*
X323471Y665657D01*
X350143D01*
X350750Y665050D01*
X368914D01*
X371457Y667593D01*
G01X368060Y667743D02*
X367958D01*
X367544Y668157D01*
X325626D01*
X318883Y674900D01*
X315000D01*
G01X370800Y475128D02*
Y474200D01*
X371200Y473800D01*
X383256D01*
X387206Y477750D01*
X390950D01*
X391582Y477118D01*
Y474189D01*
X385900Y468507D01*
Y463673D01*
X382801Y460574D01*
Y451200D01*
X386682Y447319D01*
Y436082D01*
X389500Y433264D01*
Y229500D01*
X395800Y223200D01*
Y158300D01*
X399900Y154200D01*
Y152100D01*
G01X378840Y448690D02*
X378800D01*
Y448800D01*
X383900Y443700D01*
Y435200D01*
X386620Y432480D01*
Y341720D01*
X380600Y335700D01*
G01X387500Y458200D02*
X391900D01*
X399500Y465800D01*
Y643000D01*
X383000Y659500D01*
X379037D01*
X378832Y659705D01*
G01X487500Y73400D02*
X488500Y72400D01*
Y59610D01*
X493240Y54870D01*
Y28117D01*
X493715Y27642D01*
X493716D01*
X495358Y26000D01*
X496355D01*
G01X485700Y70500D02*
X486500Y69700D01*
Y58781D01*
X491240Y54041D01*
Y27288D01*
X492886Y25642D01*
X492887D01*
X496242Y22287D01*
G01X448000Y80404D02*
X444460Y76864D01*
Y41524D01*
X463704Y22280D01*
X479190D01*
X481033Y20437D01*
X499962D01*
X501761Y22236D01*
X511564D01*
X512900Y20900D01*
X670000D01*
X677780Y28680D01*
X689116D01*
X705688Y45252D01*
X811945D01*
X825983Y59290D01*
Y396317D01*
X821800Y400500D01*
G01X444800Y82404D02*
X440908Y78512D01*
Y42247D01*
X464718Y18437D01*
X500791D01*
X502590Y20236D01*
X510735D01*
X512072Y18899D01*
X670828D01*
X678609Y26680D01*
X689945D01*
X706517Y43252D01*
X812774D01*
X827983Y58461D01*
Y397617D01*
X821700Y403900D01*
G01X471281Y105681D02*
X487562Y89400D01*
X502900D01*
X508700Y83600D01*
Y79600D01*
X519880Y68420D01*
X563921D01*
X571055Y61286D01*
X599615D01*
X608290Y69961D01*
Y77485D01*
X685372Y154567D01*
Y374037D01*
X687000Y375665D01*
Y457229D01*
X681000Y463229D01*
Y472671D01*
X695329Y487000D01*
X697700D01*
X706400Y478300D01*
X803200D01*
X804271Y477229D01*
X807400D01*
G01X473600Y108300D02*
X490500Y91400D01*
X503729D01*
X510700Y84429D01*
Y80429D01*
X520709Y70420D01*
X564750D01*
X571884Y63286D01*
X598786D01*
X606290Y70790D01*
Y78314D01*
X683372Y155396D01*
Y374866D01*
X685000Y376494D01*
Y456400D01*
X679000Y462400D01*
Y473500D01*
X694500Y489000D01*
X698529D01*
X707197Y480332D01*
X709700D01*
G01X683000Y447200D02*
Y377323D01*
X681372Y375695D01*
Y156225D01*
X598559Y73412D01*
Y69206D01*
X594639Y65286D01*
X572713D01*
X565579Y72420D01*
X523278D01*
X513300Y82398D01*
Y83000D01*
G01X503700Y107600D02*
X500000Y103900D01*
Y101700D01*
X521700Y80000D01*
Y76120D01*
X523900Y73920D01*
X566201D01*
X573213Y66908D01*
X593827D01*
X596463Y69544D01*
Y73438D01*
X679872Y156847D01*
Y376317D01*
X680600Y377045D01*
Y444700D01*
X680200Y445100D01*
Y449500D01*
G01X705450Y440950D02*
X704400Y444800D01*
X697100D01*
X693200Y440900D01*
Y369937D01*
X692172Y368909D01*
Y152472D01*
X668531Y128831D01*
Y71500D01*
G01X796100Y386700D02*
X791041Y391759D01*
X725569D01*
X721228Y396100D01*
X716743D01*
X714271Y393628D01*
Y388771D01*
X713200Y387700D01*
G01X822300Y390000D02*
X813100Y399200D01*
X720200D01*
X696400Y423000D01*
Y430000D01*
X705450Y439050D01*
Y440950D01*
G01X801200Y386700D02*
X799300Y384800D01*
X793048D01*
X788089Y389759D01*
X724740D01*
X720599Y393900D01*
X718562D01*
X717381Y392719D01*
Y388619D01*
X718300Y387700D01*
G54D11*
G01X-36569Y-23804D02*
Y-103804D01*
G01D02*
X1258031D01*
G01X-40569Y-7804D02*
G02I-12000J0D01*
G01X-45719D02*
G02I-6850J0D01*
G01X-52569Y-23804D02*
Y8196D01*
G01X-36569Y-23804D02*
X1258031D01*
G01X-36569Y-59304D02*
X1258031D01*
G01X-36569Y-7804D02*
X-68569D01*
G01X280600Y448900D02*
X276278D01*
X274478Y447100D01*
X269300D01*
X267500Y448900D01*
X239629D01*
X238744Y448015D01*
X238715D01*
X231749Y441049D01*
X209551D01*
X206300Y444300D01*
X158900D01*
X155850Y441250D01*
X108450D01*
X105704Y438504D01*
X43277D01*
X28123Y453658D01*
G01X200000Y664200D02*
X179109Y685091D01*
X156432D01*
X146400Y675059D01*
Y657723D01*
X132889Y644212D01*
X101612D01*
X93700Y636300D01*
X30870D01*
X28667Y634097D01*
G01X103940Y635460D02*
X114840D01*
X119700Y630600D01*
Y625300D01*
X116300Y621900D01*
Y607200D01*
X118250Y605250D01*
X148036D01*
X150386Y602900D01*
X181399D01*
X184400Y599899D01*
Y583800D01*
X181900Y581300D01*
Y560500D01*
X184200Y558200D01*
X188400D01*
X191000Y555600D01*
Y553971D01*
X193001Y551970D01*
X194093D01*
G01X158994Y694545D02*
X158764Y694315D01*
X150871D01*
X142127Y685571D01*
X114141D01*
X100029Y699683D01*
X94106D01*
G01X194093Y551970D02*
X197243D01*
G01X205800Y698400D02*
X202600D01*
X197100Y692900D01*
X176311D01*
X175376Y693835D01*
X169352D01*
X169351Y693834D01*
X167195D01*
X167194Y693835D01*
X159704D01*
X158994Y694545D01*
G01X266398Y679250D02*
X262228D01*
X256128Y673150D01*
X243773D01*
X240500Y676423D01*
Y676500D01*
X239400Y677600D01*
G01X272300Y665700D02*
X275204D01*
X275255Y665751D01*
X288151D01*
X290600Y668200D01*
G01X396800Y74800D02*
Y81900D01*
X366800Y111900D01*
X361500D01*
X349727Y123673D01*
Y159918D01*
X338000Y171645D01*
Y187360D01*
X334882Y190478D01*
G01X363942Y450591D02*
X360900Y447549D01*
Y410812D01*
X342738Y392650D01*
X321300D01*
X311450Y382800D01*
Y364213D01*
X312250Y363413D01*
Y228878D01*
X310100Y226728D01*
Y201132D01*
X308251Y199283D01*
X305651D01*
G01X290600Y668200D02*
X294000Y671600D01*
X307653D01*
X316923Y680870D01*
X319248D01*
X324833Y675285D01*
X336915D01*
X338293Y673907D01*
X338301D01*
G01X316465Y716063D02*
X317728Y714800D01*
X327000D01*
X330300Y711500D01*
X371900D01*
X372100Y711700D01*
G01X383600Y711800D02*
X383500Y711700D01*
X372100D01*
G01X470531Y-23804D02*
Y-103804D01*
G01X608031Y-23804D02*
Y-103804D01*
G01X680000Y23900D02*
X691055D01*
X707657Y40502D01*
X814573D01*
X830733Y56662D01*
Y336331D01*
X835316Y340914D01*
G01X723031Y-23804D02*
Y-103804D01*
G01X890531Y-23804D02*
Y-103804D01*
G01X1060531Y-23804D02*
Y-103804D01*
G01X1258031Y-23804D02*
Y-103804D01*
G01X1286031Y-7804D02*
G02I-12000J0D01*
G01X1280881D02*
G02I-6850J0D01*
G01X1274031Y-23804D02*
Y8196D01*
G01X1290031Y-7804D02*
X1258031D01*
X28123Y453658D03*
X67852Y539219D03*
X67853Y564416D03*
Y554967D03*
Y542368D03*
X28667Y634097D03*
X42550Y599224D03*
X100600Y490750D03*
X138023Y456188D03*
X140985Y454250D03*
X135262Y475726D03*
X74151Y545516D03*
X86750Y542368D03*
X126337Y554085D03*
X74498Y551757D03*
X130311Y546700D03*
X71002Y539219D03*
X74076Y535966D03*
X75508Y542198D03*
X127300Y543200D03*
X71002Y542368D03*
Y545518D03*
Y558117D03*
Y564396D03*
Y561266D03*
X75066Y563235D03*
X83600Y561265D03*
X71002Y554967D03*
X102601Y507300D03*
X78276Y545566D03*
X133554Y537374D03*
X71002Y548668D03*
X125400Y498600D03*
X83600Y573865D03*
X89899Y577014D03*
X86750D03*
X124903Y613900D03*
X124793Y617299D03*
X139500Y611200D03*
X128700Y615500D03*
X98537Y601094D03*
X102509Y601100D03*
X103109Y608572D03*
X103124Y605153D03*
X103098Y612064D03*
Y624364D03*
X113672Y605134D03*
X70700Y629000D03*
X133835Y609620D03*
X106635Y701465D03*
X94106Y699683D03*
X89868Y689124D03*
X121300Y651900D03*
X155710Y485200D03*
X172300Y478400D03*
X172900Y484101D03*
X149000Y488600D03*
X171537Y464400D03*
X179100Y455800D03*
X201600Y486500D03*
X198200D03*
X190036Y485520D03*
X194411Y485447D03*
X193400Y463300D03*
X153489Y481559D03*
X148490Y451286D03*
X144245Y452344D03*
X151877Y450439D03*
X155877D03*
X145000Y488600D03*
X166761Y498900D03*
X203610Y529397D03*
X154400Y533500D03*
X187100Y509600D03*
X195200Y513200D03*
X162537Y499000D03*
X143415Y530143D03*
X170800Y499800D03*
X200650Y497862D03*
X174700Y509600D03*
X207500Y505812D03*
X158000Y499000D03*
X200200Y529200D03*
X150553Y512500D03*
X148050Y523740D03*
X196100Y614050D03*
X203900Y614100D03*
X144737Y630882D03*
X162750Y612217D03*
X164400Y609200D03*
X182100Y629800D03*
X178200D03*
X148210Y629830D03*
X141742Y624666D03*
X144263Y609023D03*
X151800Y610300D03*
X162360Y706888D03*
X158994Y694545D03*
X205800Y698400D03*
X200000Y664200D03*
X195500Y696900D03*
X185598Y709274D03*
X182200Y709400D03*
X275276Y494017D03*
X226475Y480400D03*
X254100Y440800D03*
X257950Y440600D03*
X226500Y477000D03*
X275113Y476513D03*
X266664Y493000D03*
X231400Y489800D03*
X237903D03*
X236400Y440800D03*
X280600Y448900D03*
X214900Y490000D03*
X231476Y449662D03*
X252626Y469150D03*
X225532Y450047D03*
X237600Y455500D03*
X233664Y482859D03*
X233850Y552201D03*
X234943Y565199D03*
X265100Y562300D03*
X254494Y529198D03*
X248459Y523892D03*
X269100Y509063D03*
X228200Y496200D03*
X257894Y529254D03*
X263600Y535350D03*
X223800Y531600D03*
X236400Y502150D03*
X246508Y532821D03*
X228100Y545500D03*
X227100Y525400D03*
X238600Y509900D03*
X233100Y509800D03*
X260900Y553900D03*
X242600Y509800D03*
X233607Y557671D03*
X241154Y536017D03*
X250445Y548551D03*
X279200Y531600D03*
X257346Y599169D03*
X257332Y602569D03*
X258398Y605915D03*
Y609484D03*
X262694Y568076D03*
X261300Y571300D03*
X233447Y603747D03*
X232300Y600300D03*
X258596Y586356D03*
X259848Y583194D03*
X279214Y591383D03*
X237100Y590000D03*
X248800Y582000D03*
X268200Y578700D03*
X234800Y572000D03*
X256007Y575050D03*
X281975Y572963D03*
X279800Y569182D03*
X264200Y574100D03*
X276783Y588907D03*
X281510Y583003D03*
X276400Y700650D03*
X254900Y701950D03*
X272300Y665700D03*
X266398Y679250D03*
X239400Y677600D03*
X217638Y695562D03*
X239000Y691000D03*
X254700Y708900D03*
X268230Y723570D03*
X352000Y109000D03*
X355500D03*
X305651Y199283D03*
X320700Y177800D03*
X294720Y178600D03*
Y185600D03*
X333882Y273978D03*
Y270578D03*
X334482Y263778D03*
X333782Y267178D03*
X324000Y222800D03*
X305882Y234274D03*
X305772Y237673D03*
X334107Y287354D03*
Y283854D03*
X334582Y337721D03*
Y334221D03*
X328187Y350316D03*
Y346816D03*
X328182Y325124D03*
Y321624D03*
X334593Y312584D03*
Y309084D03*
X328182Y299977D03*
Y296477D03*
Y375518D03*
Y372018D03*
X334582Y362974D03*
Y359474D03*
X350408Y393708D03*
X348006Y391300D03*
X321859Y388315D03*
X321100Y384874D03*
X346300Y374600D03*
X349100Y379100D03*
X293326Y494174D03*
X344900Y442800D03*
X343050Y438900D03*
X339900Y454000D03*
X328313Y435513D03*
X324916Y435360D03*
X285833Y557629D03*
X293600Y518400D03*
X288311Y496200D03*
X355600Y506600D03*
X298200Y521100D03*
X301300Y524400D03*
X355600Y513500D03*
X327300Y540100D03*
X336881Y530496D03*
X307800Y546700D03*
X336953Y534506D03*
X305913Y549643D03*
X304436Y564081D03*
X307350Y561290D03*
X335000Y497000D03*
X332698Y543738D03*
X330200Y535200D03*
X331000Y522100D03*
X302665Y547006D03*
X302506Y543341D03*
X327403Y543499D03*
X327800Y514900D03*
X323400Y507540D03*
X336800Y506300D03*
X293970Y564927D03*
X335000Y500600D03*
X293500Y522600D03*
X334811Y551476D03*
X311900Y511500D03*
X312300Y540600D03*
X332940Y539287D03*
X322900Y530600D03*
X327417Y548344D03*
X290000Y503200D03*
X293800Y503300D03*
X341600Y616962D03*
Y613413D03*
X334264Y602648D03*
X337813D03*
X293500Y625600D03*
X293600Y629100D03*
X321421Y605265D03*
X303000Y586800D03*
X352716Y590535D03*
X347784Y587509D03*
X336923Y586749D03*
X347784Y584109D03*
X336923Y583349D03*
X307650Y596000D03*
X285400Y572556D03*
X317813Y580469D03*
X286400Y569200D03*
X317813Y584969D03*
X290600Y668200D03*
X338301Y673907D03*
X328600Y661100D03*
X328087Y701587D03*
X327062Y697600D03*
X332200Y643800D03*
X288720Y641455D03*
X336000Y662200D03*
X336387Y648987D03*
X317516Y671612D03*
X315000Y674900D03*
X316465Y716063D03*
X334000Y714640D03*
X342208Y714950D03*
X337481Y719818D03*
X372500Y44500D03*
Y56500D03*
Y90000D03*
Y78000D03*
X396800Y74800D03*
X399900Y152100D03*
X406400Y150300D03*
X380600Y335700D03*
X363942Y450591D03*
X366700Y454800D03*
X359400Y451600D03*
X381276Y469106D03*
X374030Y449526D03*
X372575Y452600D03*
X380200Y457800D03*
X381400Y462000D03*
X387500Y458200D03*
X370800Y475128D03*
X389081Y475224D03*
X394700Y481700D03*
X394952Y485300D03*
X378937Y443491D03*
X376697Y446050D03*
X373576Y466300D03*
X373534Y462830D03*
X370900Y471700D03*
X373700Y482700D03*
X378200Y476600D03*
X377691Y451891D03*
X381370Y465500D03*
X388123Y492432D03*
X378840Y448690D03*
X390651Y499000D03*
X397650Y508250D03*
Y536671D03*
X362280Y554590D03*
X397650Y519400D03*
X394880Y548670D03*
X397650Y523900D03*
X393465Y553100D03*
X387700Y517700D03*
X365730Y541050D03*
X368900Y505000D03*
X383126Y565162D03*
X366490Y564360D03*
X396400Y545500D03*
X390769Y495379D03*
X393889Y543207D03*
X375700Y580102D03*
X366100Y590000D03*
X366500Y586300D03*
X380572Y592095D03*
X396300Y587000D03*
X396400Y583500D03*
X395127Y568056D03*
X395100Y572899D03*
X379100Y703300D03*
X363664Y688950D03*
X378832Y659705D03*
X390500Y665800D03*
Y669200D03*
X396306Y698732D03*
X401000Y676500D03*
X371457Y667593D03*
X368060Y667743D03*
X392079Y703434D03*
X398600Y662700D03*
X383600Y711800D03*
X372100Y711700D03*
X496355Y26000D03*
X496242Y22287D03*
X432269Y19980D03*
X487500Y73400D03*
X485700Y70500D03*
X448000Y80404D03*
X444800Y82404D03*
X498500Y84200D03*
X471281Y105681D03*
X473600Y108300D03*
X459500Y95500D03*
X463479Y99412D03*
X501100Y86800D03*
X509981Y103194D03*
X505779D03*
X513300Y83000D03*
X503700Y107600D03*
X680000Y23900D03*
X668531Y71500D03*
X713200Y387700D03*
X712874Y470182D03*
X701183Y453339D03*
X704836D03*
X709700Y480332D03*
X698651Y428165D03*
X683000Y447200D03*
X680200Y449500D03*
X705450Y440950D03*
X699453Y551078D03*
X701927Y553552D03*
X684818Y543012D03*
X687292Y545486D03*
X657921Y539000D03*
X660395Y541474D03*
X678740Y508760D03*
X718300Y387700D03*
X740500Y431000D03*
X778763Y553763D03*
X781237Y556237D03*
X756263Y548263D03*
X758737Y550737D03*
X717829Y549856D03*
X720303Y552330D03*
X720536Y523519D03*
X724036D03*
X777165Y509835D03*
X820059Y331701D03*
X835316Y340914D03*
X815541Y354089D03*
X831650Y422612D03*
X794200Y422800D03*
X801200Y386700D03*
X796100D03*
X821800Y400500D03*
X821700Y403900D03*
X822300Y390000D03*
X811142Y470358D03*
X811668Y433703D03*
X807400Y477229D03*
X812763Y548263D03*
X815237Y550737D03*
X797763Y554263D03*
X800237Y556737D03*
X842369Y549234D03*
X839895Y546760D03*
G54D21*
G01X-9023Y-84471D02*
X-8149Y-83596D01*
X-7494Y-82138D01*
X-7057Y-80095D01*
X-7494Y-78346D01*
X-8367Y-77179D01*
X-9896Y-76304D01*
X-15791D01*
Y-93804D01*
X-8586D01*
X-7057Y-92638D01*
X-6184Y-90887D01*
X-5747Y-88846D01*
X-6184Y-86804D01*
X-7494Y-85054D01*
X-9023Y-84471D01*
X-15791D01*
G01X3674Y-93804D02*
Y-82138D01*
G01Y-84471D02*
X4766Y-83304D01*
X5858Y-82429D01*
X7386Y-82138D01*
X8477Y-82429D01*
X9788Y-83304D01*
G01X19646Y-99054D02*
X20956Y-99637D01*
X22703Y-99054D01*
X23794Y-97888D01*
X24668Y-96429D01*
X25977Y-91763D01*
X28816Y-82138D01*
G01X21829D02*
X25977Y-91763D01*
G01X45224Y-83596D02*
X43696Y-82429D01*
X42386Y-82138D01*
X40639Y-82721D01*
X39329Y-83887D01*
X38456Y-85929D01*
X38237Y-87971D01*
X38456Y-90013D01*
X39329Y-91763D01*
X40639Y-93221D01*
X42386Y-93804D01*
X43914Y-93221D01*
X45224Y-92054D01*
G01X55956Y-85929D02*
X62943D01*
X62288Y-83887D01*
X61196Y-82721D01*
X59668Y-82138D01*
X58139Y-82429D01*
X56829Y-83304D01*
X55956Y-85346D01*
X55519Y-87096D01*
Y-88846D01*
X55956Y-90596D01*
X57048Y-92346D01*
X58358Y-93512D01*
X59886Y-93804D01*
X61414Y-93221D01*
X62943Y-91471D01*
G01X99034Y-77763D02*
X97724Y-76887D01*
X96196Y-76304D01*
X94449D01*
X92484Y-77179D01*
X90956Y-78637D01*
X89864Y-80388D01*
X88991Y-83304D01*
X88772Y-85929D01*
X89209Y-88554D01*
X89864Y-90304D01*
X91174Y-92054D01*
X92703Y-93221D01*
X94231Y-93804D01*
X95759D01*
X97288Y-93221D01*
X98598Y-92346D01*
X99690Y-91180D01*
G01X115661Y-93804D02*
Y-82138D01*
G01Y-84179D02*
X114788Y-83013D01*
X113477Y-82429D01*
X111949Y-82138D01*
X110421Y-82721D01*
X109111Y-83887D01*
X108237Y-85637D01*
X107801Y-87971D01*
X108237Y-90304D01*
X109111Y-92054D01*
X110421Y-93221D01*
X111949Y-93804D01*
X113477Y-93512D01*
X114788Y-92638D01*
X115661Y-91471D01*
G01X125519Y-93804D02*
Y-82138D01*
G01Y-85054D02*
X126393Y-83596D01*
X127703Y-82429D01*
X129449Y-82138D01*
X130977Y-82429D01*
X132288Y-83596D01*
X132943Y-85637D01*
Y-93804D01*
G01X142146Y-99054D02*
X143456Y-99637D01*
X145203Y-99054D01*
X146294Y-97888D01*
X147168Y-96429D01*
X148477Y-91763D01*
X151316Y-82138D01*
G01X144329D02*
X148477Y-91763D01*
G01X164231Y-93804D02*
X162921Y-93512D01*
X161611Y-92346D01*
X160737Y-90304D01*
X160301Y-87971D01*
X160737Y-85637D01*
X161611Y-83596D01*
X162921Y-82429D01*
X164231Y-82138D01*
X165541Y-82429D01*
X166851Y-83596D01*
X167724Y-85637D01*
X167943Y-87971D01*
X167724Y-90304D01*
X166851Y-92346D01*
X165541Y-93512D01*
X164231Y-93804D01*
G01X178019D02*
Y-82138D01*
G01Y-85054D02*
X178893Y-83596D01*
X180203Y-82429D01*
X181949Y-82138D01*
X183477Y-82429D01*
X184788Y-83596D01*
X185443Y-85637D01*
Y-93804D01*
G01X214111Y-76304D02*
X219351D01*
G01X216731D02*
Y-93804D01*
G01X214111D02*
X219351D01*
G01X234231D02*
X232484Y-93512D01*
X230956Y-92346D01*
X229646Y-90596D01*
X228772Y-88554D01*
X228336Y-86221D01*
Y-83887D01*
X228772Y-81554D01*
X229646Y-79512D01*
X230956Y-77763D01*
X232484Y-76596D01*
X234231Y-76304D01*
X235977Y-76596D01*
X237506Y-77763D01*
X238816Y-79512D01*
X239690Y-81554D01*
X240126Y-83887D01*
Y-86221D01*
X239690Y-88554D01*
X238816Y-90596D01*
X237506Y-92346D01*
X235977Y-93512D01*
X234231Y-93804D01*
G01X246054D02*
Y-76304D01*
X251731Y-90887D01*
X257408Y-76304D01*
Y-93804D01*
G01X285639Y-99637D02*
X283456Y-96721D01*
X282364Y-93804D01*
Y-82138D01*
X283456Y-79221D01*
X285639Y-76304D01*
G01X298554Y-93804D02*
Y-76304D01*
X304231Y-90887D01*
X309908Y-76304D01*
Y-93804D01*
G01X321731Y-94387D02*
X321294Y-94096D01*
Y-93512D01*
X321731Y-93221D01*
X322168Y-93512D01*
Y-94096D01*
X321731Y-94387D01*
G01X335083Y-79221D02*
X336393Y-77471D01*
X337921Y-76596D01*
X339668Y-76304D01*
X341851Y-76887D01*
X343379Y-78346D01*
X343816Y-80095D01*
X343598Y-81846D01*
X342724Y-83304D01*
X338358Y-86221D01*
X336393Y-88262D01*
X335083Y-91180D01*
X334646Y-93804D01*
X343816D01*
G01X374231D02*
X372921Y-93512D01*
X371611Y-92346D01*
X370737Y-90304D01*
X370301Y-87971D01*
X370737Y-85637D01*
X371611Y-83596D01*
X372921Y-82429D01*
X374231Y-82138D01*
X375541Y-82429D01*
X376851Y-83596D01*
X377724Y-85637D01*
X377943Y-87971D01*
X377724Y-90304D01*
X376851Y-92346D01*
X375541Y-93512D01*
X374231Y-93804D01*
G01X388019D02*
Y-82138D01*
G01Y-85054D02*
X388893Y-83596D01*
X390203Y-82429D01*
X391949Y-82138D01*
X393477Y-82429D01*
X394788Y-83596D01*
X395443Y-85637D01*
Y-93804D01*
G01X409231D02*
Y-76304D01*
G01X422146Y-99054D02*
X423456Y-99637D01*
X425203Y-99054D01*
X426294Y-97888D01*
X427168Y-96429D01*
X428477Y-91763D01*
X431316Y-82138D01*
G01X424329D02*
X428477Y-91763D01*
G01X445323Y-99637D02*
X447506Y-96721D01*
X448598Y-93804D01*
Y-82138D01*
X447506Y-79221D01*
X445323Y-76304D01*
G01X176054Y-48804D02*
Y-31304D01*
X181731Y-45887D01*
X187408Y-31304D01*
Y-48804D01*
G01X199231D02*
X197921Y-48512D01*
X196611Y-47346D01*
X195737Y-45304D01*
X195301Y-42971D01*
X195737Y-40637D01*
X196611Y-38596D01*
X197921Y-37429D01*
X199231Y-37138D01*
X200541Y-37429D01*
X201851Y-38596D01*
X202724Y-40637D01*
X202943Y-42971D01*
X202724Y-45304D01*
X201851Y-47346D01*
X200541Y-48512D01*
X199231Y-48804D01*
G01X220661Y-31304D02*
Y-48804D01*
G01Y-46180D02*
X219788Y-47638D01*
X218477Y-48512D01*
X216949Y-48804D01*
X215203Y-48221D01*
X213893Y-46763D01*
X213019Y-45013D01*
X212801Y-42971D01*
X213019Y-40929D01*
X213893Y-39179D01*
X215203Y-37721D01*
X216949Y-37138D01*
X218477Y-37429D01*
X219569Y-38013D01*
X220661Y-39179D01*
G01X230956Y-40929D02*
X237943D01*
X237288Y-38887D01*
X236196Y-37721D01*
X234668Y-37138D01*
X233139Y-37429D01*
X231829Y-38304D01*
X230956Y-40346D01*
X230519Y-42096D01*
Y-43846D01*
X230956Y-45596D01*
X232048Y-47346D01*
X233358Y-48512D01*
X234886Y-48804D01*
X236414Y-48221D01*
X237943Y-46471D01*
G01X251731Y-48804D02*
Y-31304D01*
G01X504231Y-93804D02*
Y-76304D01*
X501611Y-79804D01*
G01Y-93804D02*
X506851D01*
G01X517583Y-86513D02*
X519111Y-84471D01*
X520421Y-83304D01*
X522168Y-82721D01*
X523696Y-83304D01*
X524788Y-84471D01*
X525661Y-86221D01*
X525879Y-88262D01*
X525661Y-90013D01*
X524788Y-91763D01*
X523477Y-93221D01*
X521949Y-93804D01*
X520203Y-93221D01*
X518674Y-91471D01*
X517801Y-88846D01*
X517583Y-85929D01*
X518019Y-82138D01*
X518674Y-80095D01*
X519766Y-78054D01*
X521294Y-76596D01*
X522823Y-76304D01*
X524351Y-76887D01*
X525443Y-78346D01*
G01X534428Y-90304D02*
X535737Y-92346D01*
X537484Y-93512D01*
X539449Y-93804D01*
X541196Y-93512D01*
X542943Y-92054D01*
X544034Y-90304D01*
X544253Y-88554D01*
X543816Y-86513D01*
X542288Y-85054D01*
X540759Y-84471D01*
X538794D01*
G01X540759D02*
X542069Y-83596D01*
X543161Y-82138D01*
X543598Y-80388D01*
X543161Y-78637D01*
X542069Y-77179D01*
X540104Y-76304D01*
X538139Y-76596D01*
X536174Y-77763D01*
G01X559351Y-93804D02*
Y-76304D01*
X551272Y-88846D01*
X562190D01*
G01X570083Y-79221D02*
X571393Y-77471D01*
X572921Y-76596D01*
X574668Y-76304D01*
X576851Y-76887D01*
X578379Y-78346D01*
X578816Y-80095D01*
X578598Y-81846D01*
X577724Y-83304D01*
X573358Y-86221D01*
X571393Y-88262D01*
X570083Y-91180D01*
X569646Y-93804D01*
X578816D01*
G01X491114Y-48804D02*
Y-31304D01*
X496354D01*
X498101Y-32179D01*
X499411Y-34221D01*
X499848Y-36554D01*
X499411Y-38887D01*
X498319Y-40637D01*
X496354Y-41513D01*
X491114D01*
G01X517784Y-32763D02*
X516474Y-31887D01*
X514946Y-31304D01*
X513199D01*
X511234Y-32179D01*
X509706Y-33637D01*
X508614Y-35388D01*
X507741Y-38304D01*
X507522Y-40929D01*
X507959Y-43554D01*
X508614Y-45304D01*
X509924Y-47054D01*
X511453Y-48221D01*
X512981Y-48804D01*
X514509D01*
X516038Y-48221D01*
X517348Y-47346D01*
X518440Y-46180D01*
G01X532227Y-39471D02*
X533101Y-38596D01*
X533756Y-37138D01*
X534193Y-35095D01*
X533756Y-33346D01*
X532883Y-32179D01*
X531354Y-31304D01*
X525459D01*
Y-48804D01*
X532664D01*
X534193Y-47638D01*
X535066Y-45887D01*
X535503Y-43846D01*
X535066Y-41804D01*
X533756Y-40054D01*
X532227Y-39471D01*
X525459D01*
G01X541431Y-54637D02*
X554531D01*
G01X560459Y-48804D02*
Y-31304D01*
X570503Y-48804D01*
Y-31304D01*
G01X582981Y-48804D02*
X581234Y-48512D01*
X579706Y-47346D01*
X578396Y-45596D01*
X577522Y-43554D01*
X577086Y-41221D01*
Y-38887D01*
X577522Y-36554D01*
X578396Y-34512D01*
X579706Y-32763D01*
X581234Y-31596D01*
X582981Y-31304D01*
X584727Y-31596D01*
X586256Y-32763D01*
X587566Y-34512D01*
X588440Y-36554D01*
X588876Y-38887D01*
Y-41221D01*
X588440Y-43554D01*
X587566Y-45596D01*
X586256Y-47346D01*
X584727Y-48512D01*
X582981Y-48804D01*
G01X633822Y-31304D02*
X639281Y-48804D01*
X644740Y-31304D01*
G01X661148Y-48804D02*
X652414D01*
Y-31304D01*
X661148D01*
G01X657654Y-39762D02*
X652414D01*
G01X669914Y-48804D02*
Y-31304D01*
X675373D01*
X677119Y-32179D01*
X678211Y-33346D01*
X678648Y-35679D01*
X678211Y-38013D01*
X676901Y-39471D01*
X675373Y-40346D01*
X669914D01*
G01X675373D02*
X678648Y-48804D01*
G01X691781Y-49387D02*
X691344Y-49096D01*
Y-48512D01*
X691781Y-48221D01*
X692218Y-48512D01*
Y-49096D01*
X691781Y-49387D01*
G01X661383Y-79221D02*
X662693Y-77471D01*
X664221Y-76596D01*
X665968Y-76304D01*
X668151Y-76887D01*
X669679Y-78346D01*
X670116Y-80095D01*
X669898Y-81846D01*
X669024Y-83304D01*
X664658Y-86221D01*
X662693Y-88262D01*
X661383Y-91180D01*
X660946Y-93804D01*
X670116D01*
G01X767364Y-31304D02*
Y-48804D01*
X776098D01*
G01X793161D02*
Y-37138D01*
G01Y-39179D02*
X792288Y-38013D01*
X790977Y-37429D01*
X789449Y-37138D01*
X787921Y-37721D01*
X786611Y-38887D01*
X785737Y-40637D01*
X785301Y-42971D01*
X785737Y-45304D01*
X786611Y-47054D01*
X787921Y-48221D01*
X789449Y-48804D01*
X790977Y-48512D01*
X792288Y-47638D01*
X793161Y-46471D01*
G01X802146Y-54054D02*
X803456Y-54637D01*
X805203Y-54054D01*
X806294Y-52888D01*
X807168Y-51429D01*
X808477Y-46763D01*
X811316Y-37138D01*
G01X804329D02*
X808477Y-46763D01*
G01X820956Y-40929D02*
X827943D01*
X827288Y-38887D01*
X826196Y-37721D01*
X824668Y-37138D01*
X823139Y-37429D01*
X821829Y-38304D01*
X820956Y-40346D01*
X820519Y-42096D01*
Y-43846D01*
X820956Y-45596D01*
X822048Y-47346D01*
X823358Y-48512D01*
X824886Y-48804D01*
X826414Y-48221D01*
X827943Y-46471D01*
G01X838674Y-48804D02*
Y-37138D01*
G01Y-39471D02*
X839766Y-38304D01*
X840858Y-37429D01*
X842386Y-37138D01*
X843477Y-37429D01*
X844788Y-38304D01*
G01X819848Y-76304D02*
Y-93804D01*
X811114D01*
G01X802129Y-86513D02*
X800601Y-84471D01*
X799291Y-83304D01*
X797544Y-82721D01*
X796016Y-83304D01*
X794924Y-84471D01*
X794051Y-86221D01*
X793833Y-88262D01*
X794051Y-90013D01*
X794924Y-91763D01*
X796235Y-93221D01*
X797763Y-93804D01*
X799509Y-93221D01*
X801038Y-91471D01*
X801911Y-88846D01*
X802129Y-85929D01*
X801693Y-82138D01*
X801038Y-80095D01*
X799946Y-78054D01*
X798418Y-76596D01*
X796889Y-76304D01*
X795361Y-76887D01*
X794269Y-78346D01*
G01X931781Y-93804D02*
X930034Y-93512D01*
X928506Y-92346D01*
X927196Y-90596D01*
X926322Y-88554D01*
X925886Y-86221D01*
Y-83887D01*
X926322Y-81554D01*
X927196Y-79512D01*
X928506Y-77763D01*
X930034Y-76596D01*
X931781Y-76304D01*
X933527Y-76596D01*
X935056Y-77763D01*
X936366Y-79512D01*
X937240Y-81554D01*
X937676Y-83887D01*
Y-86221D01*
X937240Y-88554D01*
X936366Y-90596D01*
X935056Y-92346D01*
X933527Y-93512D01*
X931781Y-93804D01*
G01X933527Y-89137D02*
X936148Y-93804D01*
G01X944478Y-76304D02*
Y-88846D01*
X945351Y-91471D01*
X947098Y-93221D01*
X949281Y-93804D01*
X951464Y-93221D01*
X953211Y-91471D01*
X954084Y-88846D01*
Y-76304D01*
G01X964161D02*
X969401D01*
G01X966781D02*
Y-93804D01*
G01X964161D02*
X969401D01*
G01X979259D02*
Y-76304D01*
X989303Y-93804D01*
Y-76304D01*
G01X1006584Y-77763D02*
X1005274Y-76887D01*
X1003746Y-76304D01*
X1001999D01*
X1000034Y-77179D01*
X998506Y-78637D01*
X997414Y-80388D01*
X996541Y-83304D01*
X996322Y-85929D01*
X996759Y-88554D01*
X997414Y-90304D01*
X998724Y-92054D01*
X1000253Y-93221D01*
X1001781Y-93804D01*
X1003309D01*
X1004838Y-93221D01*
X1006148Y-92346D01*
X1007240Y-91180D01*
G01X1019281Y-93804D02*
Y-85929D01*
X1014914Y-76304D01*
G01X1023648D02*
X1019281Y-85929D01*
G01X909478Y-48804D02*
Y-31304D01*
X913844D01*
X915591Y-32179D01*
X916901Y-33346D01*
X917993Y-35095D01*
X918866Y-37138D01*
X919084Y-40054D01*
X918866Y-42971D01*
X917993Y-45013D01*
X916901Y-46763D01*
X915591Y-47929D01*
X913844Y-48804D01*
X909478D01*
G01X928506Y-40929D02*
X935493D01*
X934838Y-38887D01*
X933746Y-37721D01*
X932218Y-37138D01*
X930689Y-37429D01*
X929379Y-38304D01*
X928506Y-40346D01*
X928069Y-42096D01*
Y-43846D01*
X928506Y-45596D01*
X929598Y-47346D01*
X930908Y-48512D01*
X932436Y-48804D01*
X933964Y-48221D01*
X935493Y-46471D01*
G01X946006Y-46763D02*
X947098Y-47929D01*
X948626Y-48804D01*
X949936D01*
X951246Y-48221D01*
X952119Y-47346D01*
X952556Y-46180D01*
X952338Y-44429D01*
X951464Y-43554D01*
X947534Y-41804D01*
X946661Y-39762D01*
X947098Y-38304D01*
X947971Y-37429D01*
X949281Y-37138D01*
X950591Y-37429D01*
X951901Y-38304D01*
G01X966781Y-37138D02*
Y-48804D01*
G01Y-32471D02*
X966344Y-32179D01*
Y-31596D01*
X966781Y-31304D01*
X967218Y-31596D01*
Y-32179D01*
X966781Y-32471D01*
G01X981224Y-53179D02*
X982753Y-54346D01*
X984499Y-54637D01*
X986027Y-54346D01*
X987338Y-52888D01*
X988211Y-50846D01*
Y-37138D01*
G01Y-39471D02*
X987338Y-38304D01*
X986027Y-37429D01*
X984499Y-37138D01*
X982753Y-37721D01*
X981661Y-38887D01*
X980787Y-40929D01*
X980351Y-42971D01*
X980569Y-44721D01*
X981443Y-46763D01*
X982753Y-48221D01*
X984499Y-48804D01*
X985809Y-48512D01*
X987338Y-47346D01*
X988211Y-46180D01*
G01X998069Y-48804D02*
Y-37138D01*
G01Y-40054D02*
X998943Y-38596D01*
X1000253Y-37429D01*
X1001999Y-37138D01*
X1003527Y-37429D01*
X1004838Y-38596D01*
X1005493Y-40637D01*
Y-48804D01*
G01X1016006Y-40929D02*
X1022993D01*
X1022338Y-38887D01*
X1021246Y-37721D01*
X1019718Y-37138D01*
X1018189Y-37429D01*
X1016879Y-38304D01*
X1016006Y-40346D01*
X1015569Y-42096D01*
Y-43846D01*
X1016006Y-45596D01*
X1017098Y-47346D01*
X1018408Y-48512D01*
X1019936Y-48804D01*
X1021464Y-48221D01*
X1022993Y-46471D01*
G01X1033724Y-48804D02*
Y-37138D01*
G01Y-39471D02*
X1034816Y-38304D01*
X1035908Y-37429D01*
X1037436Y-37138D01*
X1038527Y-37429D01*
X1039838Y-38304D01*
G01X1080481Y-76304D02*
X1078734Y-76887D01*
X1077424Y-78346D01*
X1076551Y-80095D01*
X1075896Y-82429D01*
X1075678Y-85054D01*
X1075896Y-87679D01*
X1076551Y-90013D01*
X1077424Y-91763D01*
X1078734Y-93221D01*
X1080481Y-93804D01*
X1082227Y-93221D01*
X1083538Y-91763D01*
X1084411Y-90013D01*
X1085066Y-87679D01*
X1085284Y-85054D01*
X1085066Y-82429D01*
X1084411Y-80095D01*
X1083538Y-78346D01*
X1082227Y-76887D01*
X1080481Y-76304D01*
G01X1097981Y-93804D02*
X1099509Y-93512D01*
X1101256Y-92638D01*
X1102348Y-91180D01*
X1102784Y-89137D01*
X1102348Y-87096D01*
X1101038Y-85346D01*
X1099073Y-84471D01*
X1096889D01*
X1095579Y-83887D01*
X1094487Y-82429D01*
X1094051Y-80388D01*
X1094706Y-78346D01*
X1096234Y-76887D01*
X1097981Y-76304D01*
X1099727Y-76887D01*
X1101256Y-78346D01*
X1101911Y-80388D01*
X1101474Y-82429D01*
X1100383Y-83887D01*
X1099073Y-84471D01*
X1096889D01*
X1094924Y-85346D01*
X1093614Y-87096D01*
X1093178Y-89137D01*
X1093614Y-91180D01*
X1094706Y-92638D01*
X1096453Y-93512D01*
X1097981Y-93804D01*
G01X1111551Y-94387D02*
X1119411Y-76304D01*
G01X1132981D02*
X1131234Y-76887D01*
X1129924Y-78346D01*
X1129051Y-80095D01*
X1128396Y-82429D01*
X1128178Y-85054D01*
X1128396Y-87679D01*
X1129051Y-90013D01*
X1129924Y-91763D01*
X1131234Y-93221D01*
X1132981Y-93804D01*
X1134727Y-93221D01*
X1136038Y-91763D01*
X1136911Y-90013D01*
X1137566Y-87679D01*
X1137784Y-85054D01*
X1137566Y-82429D01*
X1136911Y-80095D01*
X1136038Y-78346D01*
X1134727Y-76887D01*
X1132981Y-76304D01*
G01X1150044Y-93804D02*
X1150481Y-90013D01*
X1151136Y-86804D01*
X1152009Y-83887D01*
X1153101Y-80679D01*
X1154848Y-76304D01*
X1146114D01*
G01X1164051Y-94387D02*
X1171911Y-76304D01*
G01X1181333Y-79221D02*
X1182643Y-77471D01*
X1184171Y-76596D01*
X1185918Y-76304D01*
X1188101Y-76887D01*
X1189629Y-78346D01*
X1190066Y-80095D01*
X1189848Y-81846D01*
X1188974Y-83304D01*
X1184608Y-86221D01*
X1182643Y-88262D01*
X1181333Y-91180D01*
X1180896Y-93804D01*
X1190066D01*
G01X1202981Y-76304D02*
X1201234Y-76887D01*
X1199924Y-78346D01*
X1199051Y-80095D01*
X1198396Y-82429D01*
X1198178Y-85054D01*
X1198396Y-87679D01*
X1199051Y-90013D01*
X1199924Y-91763D01*
X1201234Y-93221D01*
X1202981Y-93804D01*
X1204727Y-93221D01*
X1206038Y-91763D01*
X1206911Y-90013D01*
X1207566Y-87679D01*
X1207784Y-85054D01*
X1207566Y-82429D01*
X1206911Y-80095D01*
X1206038Y-78346D01*
X1204727Y-76887D01*
X1202981Y-76304D01*
G01X1220481Y-93804D02*
Y-76304D01*
X1217861Y-79804D01*
G01Y-93804D02*
X1223101D01*
G01X1237544D02*
X1237981Y-90013D01*
X1238636Y-86804D01*
X1239509Y-83887D01*
X1240601Y-80679D01*
X1242348Y-76304D01*
X1233614D01*
G01X1128178Y-48804D02*
Y-31304D01*
X1132544D01*
X1134291Y-32179D01*
X1135601Y-33346D01*
X1136693Y-35095D01*
X1137566Y-37138D01*
X1137784Y-40054D01*
X1137566Y-42971D01*
X1136693Y-45013D01*
X1135601Y-46763D01*
X1134291Y-47929D01*
X1132544Y-48804D01*
X1128178D01*
G01X1154411D02*
Y-37138D01*
G01Y-39179D02*
X1153538Y-38013D01*
X1152227Y-37429D01*
X1150699Y-37138D01*
X1149171Y-37721D01*
X1147861Y-38887D01*
X1146987Y-40637D01*
X1146551Y-42971D01*
X1146987Y-45304D01*
X1147861Y-47054D01*
X1149171Y-48221D01*
X1150699Y-48804D01*
X1152227Y-48512D01*
X1153538Y-47638D01*
X1154411Y-46471D01*
G01X1167981Y-31304D02*
Y-48804D01*
G01X1164924Y-37138D02*
X1171038D01*
G01X1182206Y-40929D02*
X1189193D01*
X1188538Y-38887D01*
X1187446Y-37721D01*
X1185918Y-37138D01*
X1184389Y-37429D01*
X1183079Y-38304D01*
X1182206Y-40346D01*
X1181769Y-42096D01*
Y-43846D01*
X1182206Y-45596D01*
X1183298Y-47346D01*
X1184608Y-48512D01*
X1186136Y-48804D01*
X1187664Y-48221D01*
X1189193Y-46471D01*
G54D12*
X165745Y564567D03*
X168895D03*
X165748Y561417D03*
X162598Y558268D03*
X165748Y555118D03*
X194093Y551970D03*
X197243D03*
X212991Y561419D03*
X171906Y534661D03*
X162598Y561417D03*
X162595Y564567D03*
X209842D03*
Y561417D03*
X212992Y564567D03*
X165777Y542555D03*
X209842Y555119D03*
X175197Y548821D03*
X168898Y545669D03*
X206692Y574016D03*
X168898Y567717D03*
X159449Y570866D03*
X168898Y583464D03*
Y577165D03*
X162598Y586614D03*
X168898D03*
X159449Y577165D03*
X168898Y580315D03*
X162598Y577165D03*
X165748Y580315D03*
Y570866D03*
X162598Y567717D03*
X212992Y580315D03*
X212991Y577165D03*
X209842Y567717D03*
X212993Y592912D03*
X209842Y589763D03*
X206692Y580315D03*
X209841D03*
Y599212D03*
X159448Y589764D03*
X222441Y548820D03*
X219291D03*
X216142Y545669D03*
X216141Y589762D03*
X230600Y608100D03*
G54D22*
G01X72833Y570123D02*
X71850Y569140D01*
X70349D01*
X67853Y566644D01*
Y564416D01*
G01X88041Y553390D02*
X86067D01*
X85315Y554142D01*
X83597D01*
X83247Y554492D01*
Y555140D01*
X82897Y555490D01*
X82197D01*
X81847Y555140D01*
Y554492D01*
X81497Y554142D01*
X80797D01*
X80447Y554492D01*
Y555140D01*
X80097Y555490D01*
X79397D01*
X79047Y555140D01*
Y554492D01*
X78697Y554142D01*
X73416D01*
X72666Y553392D01*
X69428D01*
X67853Y554967D01*
G01X69743Y537857D02*
X69427Y538173D01*
Y540794D01*
X67853Y542368D01*
G01X83262Y549930D02*
X82950Y550242D01*
X82947D01*
X82695Y550494D01*
X81606D01*
X81256Y550844D01*
Y552054D01*
X80906Y552404D01*
X80206D01*
X79856Y552054D01*
Y550844D01*
X79506Y550494D01*
X78806D01*
X78456Y550844D01*
Y552054D01*
X78106Y552404D01*
X77406D01*
X77056Y552054D01*
Y550844D01*
X75752Y549540D01*
X74319D01*
X71482Y552377D01*
X68954D01*
X68026Y551449D01*
Y549397D01*
X68755Y548668D01*
X71002D01*
G01X92408Y543943D02*
X88325D01*
X86750Y542368D01*
G01X85984Y549966D02*
X85175Y550775D01*
Y552470D01*
X84253Y553392D01*
X76133D01*
X74498Y551757D01*
G01X76313Y543866D02*
X73836D01*
G02X71813Y544704I0J2861D01*
G01Y544707D01*
X71002Y545518D01*
G01X93242Y559690D02*
X84918D01*
X84568Y559340D01*
Y557680D01*
X84218Y557330D01*
X83518D01*
X83168Y557680D01*
Y559340D01*
X82818Y559690D01*
X75080D01*
X73210Y557820D01*
X71299D01*
X71002Y558117D01*
G01X73954Y569625D02*
X72577Y568248D01*
Y566587D01*
X71002Y565012D01*
Y564396D01*
G01X75066Y563235D02*
Y561363D01*
X75485Y560944D01*
X78847D01*
X79286Y561383D01*
Y567835D01*
X79696Y568245D01*
X80276D01*
X80686Y567835D01*
Y566340D01*
X81036Y565990D01*
X91490D01*
G01X91197Y562840D02*
X85175D01*
X83600Y561265D01*
G01X71002Y554967D02*
Y555972D01*
X71570Y556540D01*
X73301D01*
X73651Y556190D01*
Y555310D01*
X74001Y554960D01*
X74701D01*
X75051Y555310D01*
Y557920D01*
X75461Y558330D01*
X76041D01*
X76451Y557920D01*
Y555310D01*
X76801Y554960D01*
X77501D01*
X77851Y555310D01*
Y556190D01*
X78884Y557223D01*
Y558510D01*
X79294Y558920D01*
X79874D01*
X80284Y558510D01*
Y556890D01*
X80634Y556540D01*
X88547D01*
G01X92076Y540791D02*
X92074Y540793D01*
X85413D01*
X83858Y542348D01*
X82868D01*
X81594Y541074D01*
X81014D01*
X80604Y541484D01*
Y542064D01*
X82046Y543506D01*
Y544086D01*
X81636Y544496D01*
X81056D01*
X79543Y542983D01*
X78963D01*
X78276Y543670D01*
Y545566D01*
G54D13*
X260513Y564135D03*
G54D23*
G01X257346Y599169D02*
X258471Y600294D01*
X293980D01*
X301944Y608258D01*
X323142D01*
X326000Y605400D01*
Y601020D01*
X329686Y597334D01*
X342527D01*
X346066Y600873D01*
Y614228D01*
X344406Y615888D01*
X342674D01*
X341600Y616962D01*
G01X257332Y602569D02*
X258307Y601594D01*
X293441D01*
X301405Y609558D01*
X303642D01*
X304342Y610258D01*
X305992D01*
X306692Y609558D01*
X308342D01*
X309042Y610258D01*
X310692D01*
X311392Y609558D01*
X313042D01*
X313742Y610258D01*
X315392D01*
X316092Y609558D01*
X317742D01*
X318442Y610258D01*
X320092D01*
X320792Y609558D01*
X323681D01*
X327300Y605939D01*
Y601559D01*
X330225Y598634D01*
X332588D01*
X333288Y599334D01*
X334938D01*
X335638Y598634D01*
X337288D01*
X337988Y599334D01*
X339638D01*
X340338Y598634D01*
X341988D01*
X344766Y601412D01*
Y603948D01*
X344066Y604648D01*
Y606298D01*
X344766Y606998D01*
Y613689D01*
X343867Y614588D01*
X342775D01*
X341600Y613413D01*
G01X258398Y605915D02*
X259483Y607000D01*
X260193D01*
X262868Y604325D01*
X291163D01*
X293900Y607062D01*
X294890D01*
X296056Y608228D01*
Y609218D01*
X297223Y610385D01*
X298213D01*
X299379Y611551D01*
Y612541D01*
X300546Y613708D01*
X306198D01*
X306898Y613008D01*
X308548D01*
X309248Y613708D01*
X310898D01*
X311598Y613008D01*
X313248D01*
X313948Y613708D01*
X315598D01*
X316298Y613008D01*
X317948D01*
X318648Y613708D01*
X320298D01*
X320998Y613008D01*
X322648D01*
X323348Y613708D01*
X324998D01*
X332382Y606324D01*
X334431D01*
X335371Y605384D01*
Y603755D01*
X334264Y602648D01*
G01X258398Y609484D02*
X259582Y608300D01*
X260732D01*
X263407Y605625D01*
X290624D01*
X300007Y615008D01*
X325537D01*
X332921Y607624D01*
X334970D01*
X336671Y605923D01*
Y603790D01*
X337813Y602648D01*
G01X471260Y145670D02*
Y144170D01*
G02X470654Y143564I-606J0D01*
G01X469230D01*
G03X467067Y141401I0J-2163D01*
G01Y114706D01*
X460761Y108400D01*
X455100D01*
X447803Y101103D01*
X404747D01*
X387614Y112229D01*
X363355Y148391D01*
X360889Y159989D01*
X353345Y171606D01*
X349080Y191669D01*
X356108Y224731D01*
X345113Y276971D01*
X342369Y282464D01*
X338577Y286254D01*
X335207D01*
X334107Y287354D01*
G01X471260Y140158D02*
Y141658D01*
G03X470654Y142264I-606J0D01*
G01X469230D01*
G03X468367Y141401I0J-863D01*
G01Y114167D01*
X461300Y107100D01*
X455639D01*
X448342Y99803D01*
X404361D01*
X386682Y111283D01*
X362135Y147875D01*
X359667Y159483D01*
X352123Y171100D01*
X347750Y191669D01*
X354779Y224732D01*
X343875Y276540D01*
X341300Y281694D01*
X338038Y284954D01*
X335207D01*
X334107Y283854D01*
G01X464173Y144882D02*
Y146382D01*
G03X463567Y146988I-606J0D01*
G01X462196D01*
G03X461280Y146072I0J-916D01*
G01Y113880D01*
X458100Y110700D01*
X454739D01*
X446939Y102900D01*
X405751D01*
X389728Y113299D01*
X366425Y148156D01*
X356664Y194065D01*
X354848Y202606D01*
X359615Y225039D01*
X348347Y277990D01*
X341022Y289270D01*
X332687Y297605D01*
X329310D01*
X328182Y296477D01*
G01X464173Y150394D02*
Y148894D01*
G02X463567Y148288I-606J0D01*
G01X462196D01*
G03X459980Y146072I0J-2216D01*
G01Y114419D01*
X457561Y112000D01*
X454200D01*
X446400Y104200D01*
X406136D01*
X390660Y114244D01*
X367645Y148671D01*
X357936Y194335D01*
X356178Y202606D01*
X360945Y225039D01*
X349569Y278496D01*
X342038Y290093D01*
X333226Y298905D01*
X329254D01*
X328182Y299977D01*
G01X457086Y145670D02*
Y144170D01*
G02X456480Y143564I-606J0D01*
G01X455056D01*
G03X452893Y141401I0J-2163D01*
G01Y118793D01*
X441425Y107325D01*
X409321D01*
X393081Y117872D01*
X372830Y148255D01*
X362659Y199097D01*
X366519Y217255D01*
X350766Y294021D01*
X341661Y308039D01*
X338216Y311484D01*
X335693D01*
X334593Y312584D01*
G01X457086Y140158D02*
Y141658D01*
G03X456480Y142264I-606J0D01*
G01X455056D01*
G03X454193Y141401I0J-863D01*
G01Y118254D01*
X441964Y106025D01*
X408935D01*
X392147Y116927D01*
X371605Y147748D01*
X361331Y199105D01*
X365190Y217260D01*
X349541Y293519D01*
X340645Y307216D01*
X337677Y310184D01*
X335693D01*
X334593Y309084D01*
G01X450000Y150394D02*
Y148894D01*
G02X449394Y148288I-606J0D01*
G01X448023D01*
G03X445807Y146072I0J-2216D01*
G01Y120307D01*
X435875Y110375D01*
X419186D01*
X408594Y112566D01*
X396417Y120474D01*
X375914Y151230D01*
X368614Y187745D01*
X370737Y197733D01*
X369664Y202780D01*
X372637Y216768D01*
X356838Y294139D01*
X342103Y316242D01*
X334344Y324000D01*
X329306D01*
X328182Y325124D01*
G01X450000Y144882D02*
Y146382D01*
G03X449394Y146988I-606J0D01*
G01X448023D01*
G03X447107Y146072I0J-916D01*
G01Y119768D01*
X436414Y109075D01*
X419052D01*
X408091Y111342D01*
X395483Y119529D01*
X374689Y150723D01*
X367286Y187753D01*
X369407Y197733D01*
X368334Y202780D01*
X371309Y216773D01*
X355614Y293629D01*
X341092Y315413D01*
X333805Y322700D01*
X329258D01*
X328182Y321624D01*
G01X442913Y145670D02*
Y144170D01*
G02X442307Y143564I-606J0D01*
G01X440883D01*
G03X438720Y141401I0J-2163D01*
G01Y120559D01*
X433111Y114950D01*
X419074D01*
X411662Y116443D01*
X398917Y124719D01*
X379655Y153619D01*
X373660Y183608D01*
X378788Y207731D01*
X353928Y324711D01*
X342018Y336621D01*
X335682D01*
X334582Y337721D01*
G01X442913Y140158D02*
Y141658D01*
G03X442307Y142264I-606J0D01*
G01X440883D01*
G03X440020Y141401I0J-863D01*
G01Y120020D01*
X433650Y113650D01*
X418944D01*
X411162Y115217D01*
X410952Y115353D01*
X410953D01*
X397983Y123774D01*
X378430Y153112D01*
X372332Y183616D01*
X377458Y207731D01*
X352736Y324064D01*
X341479Y335321D01*
X335682D01*
X334582Y334221D01*
G01X435827Y150394D02*
Y148894D01*
G02X435221Y148288I-606J0D01*
G01X433850D01*
G03X431634Y146072I0J-2216D01*
G01Y120373D01*
X429673Y118412D01*
X422293D01*
X415507Y119860D01*
X402962Y128005D01*
X383221Y156547D01*
X377864Y183444D01*
X382791Y206624D01*
X357591Y327849D01*
X336239Y349200D01*
X329303D01*
X328187Y350316D01*
G01X435827Y144882D02*
Y146382D01*
G03X435221Y146988I-606J0D01*
G01X433850D01*
G03X432934Y146072I0J-916D01*
G01Y119834D01*
X430212Y117112D01*
X422155D01*
X422022Y117140D01*
X415000Y118638D01*
X402039Y127054D01*
X381998Y156029D01*
X376536Y183453D01*
X381462Y206627D01*
X356397Y327204D01*
X335700Y347900D01*
X329271D01*
X328187Y346816D01*
G01X428740Y145670D02*
Y144170D01*
G02X428134Y143564I-606J0D01*
G01X426710D01*
G03X424546Y141400I0J-2164D01*
G01Y125179D01*
X422567Y123200D01*
X421709D01*
X417393Y124119D01*
X405934Y131560D01*
X387196Y158422D01*
X382101Y183878D01*
X387110Y207442D01*
X358644Y343556D01*
X340326Y361874D01*
X335682D01*
X334582Y362974D01*
G01X428740Y140158D02*
Y141658D01*
G03X428134Y142264I-606J0D01*
G01X426710D01*
G03X425846Y141400I0J-864D01*
G01Y124640D01*
X423106Y121900D01*
X421572D01*
X416886Y122897D01*
X405013Y130608D01*
X385974Y157900D01*
X380773Y183886D01*
X385781Y207444D01*
X357450Y342911D01*
X339787Y360574D01*
X335682D01*
X334582Y359474D01*
G01X421653Y150394D02*
Y148894D01*
G02X421047Y148288I-606J0D01*
G01X401459D01*
X396011Y151924D01*
X390621Y160030D01*
X386029Y182981D01*
X391057Y206644D01*
X360832Y350507D01*
X336921Y374418D01*
X329282D01*
X328182Y375518D01*
G01X421653Y144882D02*
Y146382D01*
G03X421047Y146988I-606J0D01*
G01X401065D01*
X395072Y150987D01*
X389396Y159523D01*
X384701Y182989D01*
X389728Y206646D01*
X359639Y349861D01*
X336382Y373118D01*
X329282D01*
X328182Y372018D01*
G01X509981Y103194D02*
X509654D01*
G03X508530Y102070I0J-1124D01*
G01Y100966D01*
G03X508831Y100240I1027J0D01*
G01X511858Y97212D01*
X537229Y80734D01*
X571169D01*
X578516Y82297D01*
X585861Y83858D01*
X612058Y100872D01*
X631725Y131155D01*
X670828Y315140D01*
X664921Y342934D01*
X676150Y395765D01*
X661912Y462757D01*
X667071Y487028D01*
X666047Y491842D01*
X668302Y502447D01*
X673671Y510713D01*
X676787Y512737D01*
X681644Y513769D01*
X682183Y514599D01*
X683797Y514941D01*
X684627Y514402D01*
X686241Y514745D01*
X686780Y515575D01*
X688394Y515918D01*
X689224Y515378D01*
X690838Y515721D01*
X691377Y516552D01*
X692991Y516894D01*
X693821Y516355D01*
X695435Y516698D01*
X695974Y517528D01*
X697588Y517870D01*
X698418Y517331D01*
X705793Y518898D01*
X713489Y517263D01*
X719424Y518524D01*
X721637Y520737D01*
Y522918D01*
G03X721036Y523519I-601J0D01*
G01X720536D01*
G01X505779Y103194D02*
X506106D01*
G02X507230Y102070I0J-1124D01*
G01Y100965D01*
G03X507911Y99320I2327J0D01*
G01X511035Y96196D01*
X536843Y79434D01*
X571306D01*
X571439Y79462D01*
X586367Y82636D01*
X612998Y99932D01*
X632947Y130649D01*
X672158Y315140D01*
X666251Y342934D01*
X677480Y395765D01*
X663242Y462757D01*
X668401Y487028D01*
X667377Y491842D01*
X669524Y501941D01*
X674611Y509773D01*
X677293Y511514D01*
Y511515D01*
X698162Y515947D01*
X705793Y517568D01*
X713489Y515933D01*
X720071Y517332D01*
X722937Y520198D01*
Y522918D01*
X722938D01*
Y522921D01*
G02X723536Y523519I598J0D01*
G01X724036D01*
G01X778763Y553763D02*
X779116Y554116D01*
G03Y554962I-423J423D01*
G01Y554963D01*
X778139Y555939D01*
G02X777430Y557652I1715J1713D01*
G01Y558241D01*
X777429Y558240D01*
G03X777025Y559219I-1385J1D01*
G01X776281Y559961D01*
X775494Y560748D01*
X767091Y562389D01*
X761442Y561290D01*
X697574Y573707D01*
X646829Y563153D01*
X633518Y554174D01*
X630243Y549320D01*
X626970Y544467D01*
X622134Y519578D01*
X643318Y411890D01*
X636318Y378958D01*
X631366Y355666D01*
X626415Y332376D01*
X632017Y306021D01*
X597545Y143854D01*
X580883Y118198D01*
X566100Y108482D01*
X559189Y107100D01*
X550447D01*
X537933Y119614D01*
Y141401D01*
G02X540096Y143564I2163J0D01*
G01X541520D01*
G03X542126Y144170I0J606D01*
G01Y145670D01*
G01X781237Y556237D02*
X780884Y555884D01*
G02X780034I-425J425D01*
G01X779059Y556859D01*
G02X778730Y557653I794J794D01*
G01Y558240D01*
G03X777944Y560139I-2685J1D01*
G01X777199Y560882D01*
X776133Y561948D01*
X767091Y563714D01*
X761442Y562615D01*
X697565Y575034D01*
X646314Y564374D01*
X632581Y555111D01*
X629165Y550047D01*
X625744Y544975D01*
X620809Y519576D01*
X641991Y411900D01*
X635046Y379228D01*
X632569Y367582D01*
X625085Y332376D01*
X630687Y306021D01*
X596323Y144360D01*
X589407Y133711D01*
X588439Y133505D01*
X587540Y132122D01*
X587746Y131153D01*
X586847Y129769D01*
X585879Y129564D01*
X584980Y128180D01*
X585186Y127211D01*
X584287Y125828D01*
X583319Y125622D01*
X582420Y124238D01*
X582626Y123270D01*
X579941Y119135D01*
X565597Y109708D01*
X559060Y108400D01*
X550986D01*
X539233Y120153D01*
Y141401D01*
G02X540096Y142264I863J0D01*
G01X541520D01*
G02X542126Y141658I0J-606D01*
G01Y140158D01*
G01X756263Y548263D02*
X756616Y548616D01*
G03Y549462I-423J423D01*
G01X753156Y552922D01*
X741751Y560525D01*
X696814Y569510D01*
X649668Y559682D01*
X637057Y551176D01*
X631213Y542512D01*
X627067Y521185D01*
X649298Y408514D01*
X633346Y333412D01*
X638999Y306817D01*
X603742Y140639D01*
X587896Y116240D01*
X570010Y104535D01*
X560345Y102603D01*
X544058D01*
X530846Y115815D01*
Y146072D01*
G02X533062Y148288I2216J0D01*
G01X534433D01*
G03X535039Y148894I0J606D01*
G01Y150394D01*
G01X758737Y550737D02*
X758384Y550384D01*
G02X757534I-425J425D01*
G01X753985Y553933D01*
X742258Y561750D01*
X696809Y570837D01*
X649153Y560903D01*
X648940Y560760D01*
X648941D01*
X636120Y552113D01*
X629987Y543020D01*
X625742Y521183D01*
X647970Y408524D01*
X632016Y333412D01*
X637669Y306817D01*
X602520Y141145D01*
X600079Y137387D01*
X599111Y137181D01*
X598212Y135797D01*
X598418Y134829D01*
X597519Y133445D01*
X596551Y133239D01*
X595652Y131855D01*
X595858Y130887D01*
X594959Y129503D01*
X593991Y129297D01*
X593092Y127914D01*
X593298Y126945D01*
X586955Y117178D01*
X569508Y105761D01*
X560216Y103903D01*
X544597D01*
X532146Y116354D01*
Y146072D01*
G02X533062Y146988I916J0D01*
G01X534433D01*
G02X535039Y146382I0J-606D01*
G01Y144882D01*
G01X717829Y549856D02*
X718182Y550209D01*
G03Y551055I-423J423D01*
G01X717378Y551859D01*
Y551860D01*
G02X716660Y553594I1736J1735D01*
G01Y558192D01*
X716119Y559003D01*
X713599Y560683D01*
X693206Y564763D01*
X651625Y556105D01*
X640634Y548691D01*
X635256Y540717D01*
X632083Y524393D01*
X655254Y405189D01*
X640139Y334069D01*
X646096Y306045D01*
X611227Y142007D01*
X611177Y141772D01*
X592521Y113045D01*
X573750Y100749D01*
X564158Y98833D01*
X541367D01*
X523760Y116440D01*
Y141401D01*
G02X525923Y143564I2163J0D01*
G01X527347D01*
G03X527953Y144170I0J606D01*
G01Y145670D01*
G01X720303Y552330D02*
X719950Y551977D01*
G02X719100I-425J425D01*
G01X718298Y552779D01*
G02X717960Y553595I816J816D01*
G01Y558585D01*
X717058Y559941D01*
X714106Y561908D01*
X693201Y566090D01*
X651110Y557326D01*
X639697Y549628D01*
X634030Y541225D01*
X630758Y524393D01*
X653927Y405201D01*
X638809Y334069D01*
X644766Y306045D01*
X609955Y142278D01*
X606168Y136447D01*
X605200Y136241D01*
X604302Y134858D01*
X604507Y133889D01*
X603608Y132505D01*
X602640Y132299D01*
X601741Y130916D01*
X601947Y129947D01*
X601048Y128563D01*
X600080Y128357D01*
X599181Y126974D01*
X599387Y126005D01*
X591580Y113983D01*
X573248Y101975D01*
X564029Y100133D01*
X541906D01*
X525060Y116979D01*
Y141401D01*
G02X525923Y142264I863J0D01*
G01X527347D01*
G02X527953Y141658I0J-606D01*
G01Y140158D01*
G01X699453Y551078D02*
X699806Y551431D01*
G03Y552277I-423J423D01*
G02X699804Y552279I1344J1346D01*
G01X698093Y553991D01*
X694703Y559020D01*
X693123Y559849D01*
X691812Y560104D01*
X682627Y558274D01*
X673444Y556445D01*
X655078Y552786D01*
X644596Y545715D01*
X639441Y538071D01*
X636276Y521837D01*
X660929Y401511D01*
X647190Y336873D01*
X653307Y308083D01*
X617377Y139048D01*
X598258Y109607D01*
X579293Y97219D01*
X567612Y94882D01*
X538779D01*
X516673Y116988D01*
Y146072D01*
G02X518889Y148288I2216J0D01*
G01X520260D01*
G03X520866Y148894I0J606D01*
G01Y150394D01*
G01X701927Y553552D02*
X701574Y553199D01*
G02X700724I-425J425D01*
G01X699101Y554822D01*
X695598Y560020D01*
X693558Y561089D01*
X691809Y561429D01*
X654567Y554011D01*
X643659Y546652D01*
X638215Y538579D01*
X634950Y521831D01*
X659600Y401516D01*
X645860Y336873D01*
X651977Y308083D01*
X616155Y139554D01*
X608725Y128113D01*
X607757Y127907D01*
X606858Y126523D01*
X607064Y125555D01*
X606165Y124171D01*
X605197Y123965D01*
X604298Y122582D01*
X604504Y121613D01*
X603605Y120229D01*
X602637Y120024D01*
X601739Y118640D01*
X601944Y117671D01*
X597317Y110546D01*
X578792Y98445D01*
X567483Y96182D01*
X539318D01*
X517973Y117527D01*
Y146072D01*
G02X518889Y146988I916J0D01*
G01X520260D01*
G02X520866Y146382I0J-606D01*
G01Y144882D01*
G01X684818Y543012D02*
X685171Y543365D01*
G03Y544211I-423J423D01*
G01X684530Y544852D01*
G03X683540Y545118I-990J-1709D01*
G02X681014Y546111I-1J3706D01*
G01X680431Y546694D01*
G02X679520Y548121I2774J2775D01*
G02X679388Y548873I2057J749D01*
G01Y549994D01*
G03X677819Y552272I-2438J0D01*
G01X676500Y552529D01*
X674589Y552901D01*
X658197Y549713D01*
X648301Y543038D01*
X643474Y535882D01*
X641023Y523275D01*
X666831Y397919D01*
X654086Y337951D01*
X659992Y310169D01*
X622799Y135158D01*
X604107Y106372D01*
X582066Y92058D01*
X568423Y89100D01*
X539114D01*
X509586Y118628D01*
Y141401D01*
G02X511749Y143564I2163J0D01*
G01X513173D01*
G03X513779Y144170I0J606D01*
G01Y145670D01*
G01X687292Y545486D02*
X686939Y545133D01*
G02X686089I-425J425D01*
G01X685427Y545795D01*
G03X685182Y545977I-917J-978D01*
G03X683540Y546418I-1641J-2834D01*
G02X681916Y547049I0J2405D01*
G01X681351Y547614D01*
G02X680742Y548568I1854J1855D01*
G02X680688Y548873I834J305D01*
G01Y549994D01*
G03X678282Y553487I-3739J0D01*
G02X678191Y553524I810J2123D01*
G01X674589Y554226D01*
X657948Y550989D01*
Y550990D01*
X657689Y550939D01*
X657469Y550791D01*
X647364Y543975D01*
X642248Y536390D01*
X639697Y523268D01*
X665502Y397923D01*
X652756Y337951D01*
X658662Y310169D01*
X621577Y135664D01*
X616277Y127502D01*
X615309Y127296D01*
X614410Y125912D01*
X614616Y124944D01*
X613717Y123560D01*
X612749Y123354D01*
X611850Y121970D01*
X612056Y121002D01*
X611158Y119618D01*
X610189Y119412D01*
X609291Y118028D01*
X609497Y117060D01*
X608598Y115676D01*
X607630Y115470D01*
X606731Y114086D01*
X606937Y113118D01*
X603167Y107312D01*
X581557Y93279D01*
X568283Y90400D01*
X539653D01*
X510886Y119167D01*
Y141401D01*
G02X511749Y142264I863J0D01*
G01X513173D01*
G02X513779Y141658I0J-606D01*
G01Y140158D01*
G01X657921Y539000D02*
X658274Y539353D01*
G03Y540199I-423J423D01*
G01X657354Y541119D01*
G03X654479I-1438J-1437D01*
G01X647746Y534387D01*
X645470Y522669D01*
X672504Y395532D01*
X660640Y339717D01*
X666604Y311659D01*
X628338Y131665D01*
X609963Y103370D01*
X584641Y86922D01*
X571436Y84100D01*
X538824D01*
X502500Y120424D01*
Y146072D01*
G02X504716Y148288I2216J0D01*
G01X506087D01*
G03X506693Y148894I0J606D01*
G01Y150394D01*
G01X660395Y541474D02*
X660042Y541121D01*
G02X659192I-425J425D01*
G01X658274Y542039D01*
G03X653559I-2358J-2358D01*
G01X646664Y535145D01*
G03X646661Y535142I387J-390D01*
G01X646545Y535026D01*
X644143Y522657D01*
X671174Y395532D01*
X659310Y339717D01*
X665274Y311659D01*
X627116Y132171D01*
X620314Y121698D01*
X619346Y121492D01*
X618447Y120108D01*
X618653Y119140D01*
X617755Y117756D01*
X616786Y117550D01*
X615888Y116166D01*
X616093Y115198D01*
X615195Y113814D01*
X614226Y113608D01*
X613328Y112224D01*
X613534Y111256D01*
X609023Y104310D01*
X584134Y88144D01*
X571298Y85400D01*
X539363D01*
X503800Y120963D01*
Y146072D01*
G02X504716Y146988I916J0D01*
G01X506087D01*
G02X506693Y146382I0J-606D01*
G01Y144882D01*
G01X812763Y548263D02*
X813116Y548616D01*
G03Y549462I-423J423D01*
G01X811994Y550584D01*
G02X811993Y554492I1955J1955D01*
G01X811994D01*
X814985Y557483D01*
Y561152D01*
X813975Y562668D01*
X810141Y565225D01*
X791586Y568936D01*
X774323Y572388D01*
X774320D01*
X757966Y569209D01*
X698819Y580706D01*
X641564Y569575D01*
X626202Y559213D01*
X618923Y548423D01*
X612685Y516327D01*
X632128Y417404D01*
X613141Y328077D01*
X618503Y302842D01*
X585744Y148724D01*
X571132Y126216D01*
X568590Y123674D01*
X560110Y118022D01*
X556496Y117300D01*
X554461D01*
X552106Y119655D01*
Y141401D01*
G02X554269Y143564I2163J0D01*
G01X555693D01*
G03X556299Y144170I0J606D01*
G01Y145670D01*
G01X815237Y550737D02*
X814884Y550384D01*
G02X814034I-425J425D01*
G01X812914Y551504D01*
G02Y553573I1035J1035D01*
G01X816285Y556944D01*
Y561546D01*
X814913Y563606D01*
X810649Y566450D01*
X791841Y570211D01*
X785729Y571433D01*
X779614Y572656D01*
X776016Y573376D01*
X774324Y573714D01*
X757966Y570534D01*
X698819Y582031D01*
X641056Y570801D01*
X625265Y560150D01*
X617697Y548931D01*
X611360Y516326D01*
X630801Y417414D01*
X611811Y328077D01*
X617173Y302842D01*
X584522Y149230D01*
X579535Y141548D01*
X578567Y141342D01*
X577668Y139958D01*
X577874Y138990D01*
X576976Y137606D01*
X576008Y137400D01*
X575109Y136016D01*
X575315Y135048D01*
X574417Y133664D01*
X573448Y133458D01*
X572550Y132074D01*
X572756Y131106D01*
X570116Y127039D01*
X567765Y124688D01*
X559603Y119247D01*
X556367Y118600D01*
X555000D01*
X553406Y120194D01*
Y141401D01*
G02X554269Y142264I863J0D01*
G01X555693D01*
G02X556299Y141658I0J-606D01*
G01Y140158D01*
G01X797763Y554263D02*
X798116Y554616D01*
G03Y555462I-423J423D01*
G01X797289Y556289D01*
G02X796680Y557763I1474J1472D01*
G01Y559406D01*
G03X795586Y561802I-3171J0D01*
G01X794265Y563121D01*
X770796Y567687D01*
X758981Y565392D01*
X699329Y577321D01*
X643837Y565799D01*
X629439Y556087D01*
X623126Y546727D01*
X617464Y517603D01*
X637606Y415102D01*
X619665Y330677D01*
X625435Y303521D01*
X592322Y147723D01*
X575479Y121786D01*
X563610Y113873D01*
X558978Y112947D01*
X551514D01*
X545019Y119442D01*
Y146072D01*
G02X547235Y148288I2216J0D01*
G01X548606D01*
G03X549212Y148894I0J606D01*
G01Y150394D01*
G01X800237Y556737D02*
X799884Y556384D01*
G02X799034I-425J425D01*
G01X798209Y557209D01*
G02X797980Y557762I553J553D01*
G01Y559406D01*
G03X796475Y562752I-4472J0D01*
G01X794903Y564322D01*
X770796Y569012D01*
X758985Y566718D01*
X699324Y578648D01*
X643573Y567072D01*
X643572D01*
X643322Y567020D01*
X628502Y557024D01*
X621900Y547235D01*
X616139Y517602D01*
X636279Y415112D01*
X618335Y330677D01*
X624105Y303521D01*
X591100Y148229D01*
X586758Y141543D01*
X585790Y141338D01*
X584891Y139954D01*
X585097Y138986D01*
X584198Y137602D01*
X583230Y137396D01*
X582331Y136012D01*
X582537Y135044D01*
X581638Y133660D01*
X580670Y133454D01*
X579772Y132070D01*
X579977Y131102D01*
X574534Y122720D01*
X563103Y115098D01*
X558849Y114247D01*
X552053D01*
X546319Y119981D01*
Y146072D01*
G02X547235Y146988I916J0D01*
G01X548606D01*
G02X549212Y146382I0J-606D01*
G01Y144882D01*
G01X842369Y549234D02*
X842016Y548881D01*
G02X841166I-425J425D01*
G01X838873Y551174D01*
G02X837781Y553810I2636J2636D01*
G01Y555950D01*
X837782D01*
G03X836152Y559884I-5560J1D01*
G01X836028Y560006D01*
X824460Y571574D01*
X773493Y582409D01*
X755794Y578647D01*
X754450Y578932D01*
Y578933D01*
X704608Y589526D01*
X638206Y575411D01*
X621901Y564823D01*
X612616Y550526D01*
X608658Y531904D01*
X604691Y513246D01*
X609377Y491205D01*
X614006Y469433D01*
X618984Y446016D01*
Y446015D01*
X623963Y422596D01*
X604226Y329753D01*
X607085Y316306D01*
X609829Y303399D01*
X586948Y195761D01*
X569577Y175588D01*
X561178Y171910D01*
X556905D01*
G02X556299Y172516I0J606D01*
G01Y174016D01*
G01X839895Y546760D02*
X840248Y547113D01*
G03Y547959I-423J423D01*
G01X837953Y550254D01*
G02X836481Y553810I3556J3555D01*
G01Y555950D01*
G03X835234Y558962I-4259J1D01*
G01X835112Y559083D01*
X823813Y570382D01*
X821248Y570927D01*
X820418Y570388D01*
X818804Y570731D01*
X818265Y571561D01*
X816651Y571904D01*
X815821Y571365D01*
X814207Y571708D01*
X813668Y572538D01*
X812054Y572881D01*
X811224Y572342D01*
X809610Y572685D01*
X809071Y573515D01*
X807457Y573858D01*
X806627Y573319D01*
X805013Y573662D01*
X804474Y574492D01*
X773493Y581079D01*
X755794Y577317D01*
X754180Y577660D01*
X753350Y577121D01*
X751736Y577464D01*
X751197Y578294D01*
X749583Y578637D01*
X748753Y578098D01*
X747139Y578441D01*
X746600Y579271D01*
X744986Y579614D01*
X744156Y579075D01*
X742542Y579418D01*
X742003Y580248D01*
X704608Y588196D01*
X638712Y574189D01*
X622841Y563883D01*
X613838Y550020D01*
X606021Y513246D01*
X615278Y469703D01*
X625293Y422596D01*
X605556Y329753D01*
X611159Y303399D01*
X588151Y195165D01*
X570370Y174515D01*
X561451Y170610D01*
X556905D01*
G03X556299Y170004I0J-606D01*
G01Y168504D01*
G54D14*
X353543Y70787D03*
G54D15*
X421653Y144882D03*
X428740Y140158D03*
X421653Y150394D03*
X428740Y145670D03*
X421653Y159055D03*
X435827Y144882D03*
X442913Y140158D03*
X450000Y144882D03*
X457086Y140158D03*
X464173Y144882D03*
X471260Y140158D03*
X435827Y150394D03*
X442913Y145670D03*
X450000Y150394D03*
X457086Y145670D03*
X464173Y150394D03*
X471260Y145670D03*
X506693Y144882D03*
X513779Y140158D03*
X520866Y144882D03*
X527953Y140158D03*
X535039Y144882D03*
X542126Y140158D03*
X549212Y144882D03*
X556299Y140158D03*
X506693Y150394D03*
X513779Y145670D03*
X520866Y150394D03*
X527953Y145670D03*
X535039Y150394D03*
X542126Y145670D03*
X549212Y150394D03*
X556299Y145670D03*
Y168504D03*
Y174016D03*
G54D16*
Y179528D03*
G54D17*
G01X162360Y706888D02*
X159388D01*
X153093Y700593D01*
X141348D01*
X137689Y696934D01*
X114323D01*
X109792Y701465D01*
X106635D01*
G01X89868Y689124D02*
X100395D01*
X109448Y680071D01*
Y659056D01*
X116604Y651900D01*
X121300D01*
G01X162360Y706888D02*
X175440D01*
X175577Y707025D01*
X177317D01*
X177454Y706888D01*
X186588D01*
X188300Y708600D01*
X238700D01*
X240432Y706868D01*
X249468D01*
X266170Y723570D01*
X268230D01*
G01X396306Y698732D02*
X392709D01*
X385705Y705736D01*
X327179D01*
X321247Y699804D01*
X302914D01*
X300810Y697700D01*
X295986D01*
X295882Y697804D01*
X293726D01*
X293622Y697700D01*
X281800D01*
X277381Y693281D01*
X265968D01*
X262549Y696700D01*
X253655D01*
X248455Y701900D01*
X200500D01*
X195500Y696900D01*
G01X268230Y723570D02*
X292332D01*
X297429Y718473D01*
X312934D01*
X314061Y719600D01*
X329040D01*
X334000Y714640D01*
G01X459500Y95500D02*
X458900D01*
X448500Y85100D01*
X444000D01*
X438658Y79758D01*
Y39310D01*
X431126Y31778D01*
Y21123D01*
X432269Y19980D01*
G54D18*
G01X663601Y51761D02*
Y128393D01*
X689172Y153964D01*
Y370152D01*
X690200Y371180D01*
Y442143D01*
X696900Y448843D01*
Y457561D01*
X689875Y464586D01*
G01X712874Y470182D02*
X723363D01*
X726697Y473516D01*
X801084D01*
X804242Y470358D01*
X811142D01*
G01X740500Y431000D02*
X779693D01*
X787893Y422800D01*
X794200D01*
G01X809000Y429400D02*
Y428466D01*
X814854Y422612D01*
X831650D01*
G01X811668Y433703D02*
Y432988D01*
X809000Y430320D01*
Y429400D01*
G01X811668Y433703D02*
Y469832D01*
X811142Y470358D01*
G54D19*
G01X165748Y555118D02*
X164996Y554367D01*
Y553596D01*
X164200Y552800D01*
Y551200D01*
X163400Y550400D01*
X158460D01*
X155343Y547283D01*
G01X157875Y552624D02*
X158869Y553618D01*
X163219D01*
X164097Y554496D01*
Y554497D01*
X164099Y554499D01*
Y557597D01*
X164098Y557598D01*
Y559097D01*
X165748Y560747D01*
Y561417D01*
M02*
